FILE_TYPE = MACRO_DRAWING;
SET COLOR_WIRE YELLOW;
SET COLOR_PROP MONO;
SET COLOR_DOT WHITE;
SET COLOR_ARC YELLOW;
SET COLOR_BODY GREEN;
SET COLOR_NOTE MONO;
SET PROP_DISPLAY VALUE;
SET PAGE_NUMBER P186;
FORCEADD CAP_A..1
(10850 4675);
FORCEPROP 1 LAST LOCATION C1M24
J 0
(10900 4775);
DISPLAY 0.617021 (10900 4775);
PAINT AQUA (10900 4775);
FORCEPROP 1 LAST TOLERANCE 10%
J 0
(10900 4625);
DISPLAY 0.617021 (10900 4625);
PAINT SKYBLUE (10900 4625);
FORCEPROP 1 LAST PACK_TYPE 0402V
J 0
(10900 4475);
DISPLAY 0.617021 (10900 4475);
PAINT SKYBLUE (10900 4475);
FORCEPROP 1 LAST VOLTAGE 16V
J 0
(10900 4675);
DISPLAY 0.617021 (10900 4675);
PAINT SKYBLUE (10900 4675);
FORCEPROP 1 LASTPIN (10850 4775) $PN 1
J 0
(10860 4755);
DISPLAY 0.617021 (10860 4755);
PAINT ORANGE (10860 4755);
FORCEPROP 1 LAST PART_NUMBER A36096-030
J 0
(10900 4525);
DISPLAY 0.617021 (10900 4525);
PAINT BLUE (10900 4525);
FORCEPROP 1 LAST MATERIAL X7R
J 0
(10900 4575);
DISPLAY 0.617021 (10900 4575);
PAINT SKYBLUE (10900 4575);
FORCEPROP 1 LASTPIN (10850 4575) $PN 2
J 0
(10860 4555);
DISPLAY 0.617021 (10860 4555);
PAINT ORANGE (10860 4555);
FORCEPROP 1 LAST VALUE 0.1UF
J 0
(10900 4725);
DISPLAY 0.617021 (10900 4725);
PAINT SKYBLUE (10900 4725);
FORCEPROP 0 LAST ROOM IO_SLOT
J 0
(10900 4875);
DISPLAY 1.021277 (10900 4875);
PAINT ORANGE (10900 4875);
DISPLAY INVISIBLE (10900 4875);
FORCEPROP 2 LAST SEC 1
J 0
(10900 4875);
DISPLAY 0.680851 (10900 4875);
PAINT MONO (10900 4875);
DISPLAY INVISIBLE (10900 4875);
FORCEPROP 2 LAST SEC_TYPE 0402V
J 0
(10900 4875);
DISPLAY 1.021277 (10900 4875);
PAINT ORANGE (10900 4875);
DISPLAY INVISIBLE (10900 4875);
FORCEPROP 2 LAST CDS_SEC 1
J 0
(10900 4825);
PAINT ORANGE (10900 4825);
DISPLAY INVISIBLE (10900 4825);
FORCEPROP 2 LAST CDS_LIB dev_discrete
J 0
(10850 4675);
PAINT ORANGE (10850 4675);
DISPLAY INVISIBLE (10850 4675);
FORCEPROP 2 LAST CDS_LOCATION C1M24
J 0
(10900 4775);
DISPLAY 0.617021 (10900 4775);
PAINT AQUA (10900 4775);
DISPLAY INVISIBLE (10900 4775);
FORCEPROP 1 LAST PATH I10
J 0
(10900 4825);
DISPLAY 0.978723 (10900 4825);
PAINT WHITE (10900 4825);
DISPLAY INVISIBLE (10900 4825);
FORCEADD GND..1
(11650 3550);
FORCEPROP 3 LASTPIN (11650 3600) SIG_NAME GND\g
J 0
(11660 3610);
DISPLAY 0.659574 (11660 3610);
PAINT MONO (11660 3610);
DISPLAY INVISIBLE (11660 3610);
FORCEPROP 1 LAST VOLTAGE 0
J 0
(11650 3550);
PAINT SKYBLUE (11650 3550);
DISPLAY INVISIBLE (11650 3550);
FORCEPROP 1 LAST HDL_POWER GND
J 0
(11650 3700);
DISPLAY 0.872340 (11650 3700);
PAINT GREEN (11650 3700);
DISPLAY INVISIBLE (11650 3700);
FORCEPROP 1 LAST PATH I14
J 0
(11725 3550);
DISPLAY 0.872340 (11725 3550);
PAINT AQUA (11725 3550);
DISPLAY INVISIBLE (11725 3550);
FORCEPROP 1 LAST BODY_TYPE PLUMBING
J 0
(11605 3507);
DISPLAY 0.340426 (11605 3507);
PAINT GREEN (11605 3507);
DISPLAY INVISIBLE (11605 3507);
FORCEPROP 1 LAST SIZE 1B
J 0
(11725 3500);
DISPLAY 0.872340 (11725 3500);
PAINT AQUA (11725 3500);
DISPLAY INVISIBLE (11725 3500);
FORCEPROP 2 LAST CDS_LIB mstr_symbols
J 0
(11650 3550);
PAINT ORANGE (11650 3550);
DISPLAY INVISIBLE (11650 3550);
FORCEADD GND..1
(7525 700);
FORCEPROP 3 LASTPIN (7525 750) SIG_NAME GND\g
J 0
(7535 760);
DISPLAY 0.659574 (7535 760);
PAINT MONO (7535 760);
DISPLAY INVISIBLE (7535 760);
FORCEPROP 1 LAST VOLTAGE 0
J 0
(7525 700);
PAINT SKYBLUE (7525 700);
DISPLAY INVISIBLE (7525 700);
FORCEPROP 1 LAST HDL_POWER GND
J 0
(7525 850);
DISPLAY 0.872340 (7525 850);
PAINT GREEN (7525 850);
DISPLAY INVISIBLE (7525 850);
FORCEPROP 1 LAST PATH I192
J 0
(7600 700);
DISPLAY 0.872340 (7600 700);
PAINT AQUA (7600 700);
DISPLAY INVISIBLE (7600 700);
FORCEPROP 1 LAST BODY_TYPE PLUMBING
J 0
(7480 657);
DISPLAY 0.340426 (7480 657);
PAINT GREEN (7480 657);
DISPLAY INVISIBLE (7480 657);
FORCEPROP 1 LAST SIZE 1B
J 0
(7600 650);
DISPLAY 0.872340 (7600 650);
PAINT AQUA (7600 650);
DISPLAY INVISIBLE (7600 650);
FORCEPROP 2 LAST CDS_LIB mstr_symbols
J 0
(7525 700);
PAINT ORANGE (7525 700);
DISPLAY INVISIBLE (7525 700);
FORCEADD GND..1
(8975 725);
FORCEPROP 3 LASTPIN (8975 775) SIG_NAME GND\g
J 0
(8985 785);
DISPLAY 0.659574 (8985 785);
PAINT MONO (8985 785);
DISPLAY INVISIBLE (8985 785);
FORCEPROP 1 LAST VOLTAGE 0
J 0
(8975 725);
PAINT SKYBLUE (8975 725);
DISPLAY INVISIBLE (8975 725);
FORCEPROP 1 LAST HDL_POWER GND
J 0
(8975 875);
DISPLAY 0.872340 (8975 875);
PAINT GREEN (8975 875);
DISPLAY INVISIBLE (8975 875);
FORCEPROP 1 LAST PATH I193
J 0
(9050 725);
DISPLAY 0.872340 (9050 725);
PAINT AQUA (9050 725);
DISPLAY INVISIBLE (9050 725);
FORCEPROP 1 LAST BODY_TYPE PLUMBING
J 0
(8930 682);
DISPLAY 0.340426 (8930 682);
PAINT GREEN (8930 682);
DISPLAY INVISIBLE (8930 682);
FORCEPROP 2 LAST CDS_LIB mstr_symbols
J 0
(8975 725);
PAINT ORANGE (8975 725);
DISPLAY INVISIBLE (8975 725);
FORCEPROP 1 LAST SIZE 1B
J 0
(9050 675);
DISPLAY 0.872340 (9050 675);
PAINT AQUA (9050 675);
DISPLAY INVISIBLE (9050 675);
FORCEADD P3V3..1
(7000 3500);
FORCEPROP 3 LASTPIN (7000 3450) SIG_NAME P3V3\g
J 0
(7010 3460);
DISPLAY 0.659574 (7010 3460);
PAINT MONO (7010 3460);
DISPLAY INVISIBLE (7010 3460);
FORCEPROP 1 LAST VOLTAGE +3.3
J 0
(7000 3500);
PAINT SKYBLUE (7000 3500);
DISPLAY INVISIBLE (7000 3500);
FORCEPROP 1 LAST HDL_POWER P3V3
J 0
(6675 3375);
DISPLAY 1.170213 (6675 3375);
PAINT GREEN (6675 3375);
DISPLAY INVISIBLE (6675 3375);
FORCEPROP 1 LAST PATH I195
J 0
(7045 3502);
DISPLAY 0.340426 (7045 3502);
PAINT GREEN (7045 3502);
DISPLAY INVISIBLE (7045 3502);
FORCEPROP 1 LAST BODY_TYPE PLUMBING
J 0
(6955 3457);
DISPLAY 0.468085 (6955 3457);
PAINT GREEN (6955 3457);
DISPLAY INVISIBLE (6955 3457);
FORCEPROP 1 LAST SIZE 1B
J 0
(7045 3522);
DISPLAY 0.468085 (7045 3522);
PAINT GREEN (7045 3522);
DISPLAY INVISIBLE (7045 3522);
FORCEPROP 2 LAST CDS_LIB mstr_symbols
J 0
(7000 3500);
PAINT ORANGE (7000 3500);
DISPLAY INVISIBLE (7000 3500);
FORCEADD OFFPAGE..3
(9750 3100);
FORCEPROP 2 LAST $XR3 188 
J 0
(10294 3100);
DISPLAY 0.638298 (10294 3100);
PAINT MONO (10294 3100);
FORCEPROP 2 LAST $XR2 159 
J 0
(10174 3100);
DISPLAY 0.638298 (10174 3100);
PAINT MONO (10174 3100);
FORCEPROP 2 LAST $XR1 138 
J 0
(10054 3100);
DISPLAY 0.638298 (10054 3100);
PAINT MONO (10054 3100);
FORCEPROP 2 LAST $XR0 91 
J 0
(9964 3100);
DISPLAY 0.638298 (9964 3100);
PAINT MONO (9964 3100);
FORCEPROP 2 LAST CDS_LIB mstr_standard
J 2
(9750 3100);
PAINT ORANGE (9750 3100);
DISPLAY INVISIBLE (9750 3100);
FORCEPROP 1 LAST OFFPAGE TRUE
J 0
(10075 2975);
DISPLAY 0.872340 (10075 2975);
PAINT GREEN (10075 2975);
DISPLAY INVISIBLE (10075 2975);
FORCEPROP 1 LAST COMMENT_BODY TRUE
J 0
(9700 3000);
DISPLAY 0.872340 (9700 3000);
PAINT GREEN (9700 3000);
DISPLAY INVISIBLE (9700 3000);
FORCEPROP 2 LAST PATH I217
J 2
(9575 3175);
DISPLAY 1.021277 (9575 3175);
PAINT ORANGE (9575 3175);
DISPLAY INVISIBLE (9575 3175);
FORCEADD RES..1
(6000 3050);
FORCEPROP 1 LASTPIN (6100 3050) $PN 2
J 0
(6062 3062);
DISPLAY 0.617021 (6062 3062);
PAINT ORANGE (6062 3062);
FORCEPROP 1 LAST LOCATION R1M14
J 0
(5950 3100);
DISPLAY 0.617021 (5950 3100);
PAINT AQUA (5950 3100);
FORCEPROP 1 LASTPIN (5900 3050) $PN 1
J 0
(5912 3062);
DISPLAY 0.617021 (5912 3062);
PAINT ORANGE (5912 3062);
FORCEPROP 1 LAST PART_NUMBER G21796-004
J 0
(5825 3000);
DISPLAY 0.617021 (5825 3000);
PAINT BLUE (5825 3000);
FORCEPROP 1 LAST VALUE 200.0
J 2
(5975 2950);
DISPLAY 0.617021 (5975 2950);
PAINT SKYBLUE (5975 2950);
FORCEPROP 1 LAST WATTAGE 1/16W
J 2
(5975 2900);
DISPLAY 0.617021 (5975 2900);
PAINT SKYBLUE (5975 2900);
FORCEPROP 1 LAST MATERIAL CHIP
J 0
(6000 2900);
DISPLAY 0.617021 (6000 2900);
PAINT SKYBLUE (6000 2900);
FORCEPROP 1 LAST TOLERANCE 1%
J 0
(6000 2950);
DISPLAY 0.617021 (6000 2950);
PAINT SKYBLUE (6000 2950);
FORCEPROP 1 LAST PACK_TYPE 0402
J 0
(6100 2975);
DISPLAY 0.617021 (6100 2975);
PAINT SKYBLUE (6100 2975);
FORCEPROP 0 LAST ROOM IO_SLOT
J 0
(5950 3250);
DISPLAY 1.021277 (5950 3250);
PAINT ORANGE (5950 3250);
DISPLAY INVISIBLE (5950 3250);
FORCEPROP 1 LAST PATH I220
J 0
(5950 3200);
DISPLAY 0.978723 (5950 3200);
PAINT WHITE (5950 3200);
DISPLAY INVISIBLE (5950 3200);
FORCEPROP 2 LAST CDS_LOCATION R1M14
J 0
(5950 3100);
DISPLAY 0.617021 (5950 3100);
PAINT AQUA (5950 3100);
DISPLAY INVISIBLE (5950 3100);
FORCEPROP 2 LAST SEC 1
J 0
(5950 3250);
DISPLAY 0.680851 (5950 3250);
PAINT MONO (5950 3250);
DISPLAY INVISIBLE (5950 3250);
FORCEPROP 2 LAST CDS_LIB mstr_discrete
J 0
(6000 3050);
PAINT MONO (6000 3050);
DISPLAY INVISIBLE (6000 3050);
FORCEPROP 2 LAST SEC_TYPE 0402
J 0
(5950 3250);
DISPLAY 1.021277 (5950 3250);
PAINT ORANGE (5950 3250);
DISPLAY INVISIBLE (5950 3250);
FORCEADD OFFPAGE..1
(5150 3050);
FORCEPROP 2 LAST $XR0 191 
J 0
(4898 3050);
DISPLAY 0.638298 (4898 3050);
PAINT MONO (4898 3050);
FORCEPROP 2 LAST CDS_LIB mstr_standard
J 0
(5150 3050);
PAINT ORANGE (5150 3050);
DISPLAY INVISIBLE (5150 3050);
FORCEPROP 1 LAST OFFPAGE TRUE
J 0
(5475 2925);
DISPLAY 0.872340 (5475 2925);
PAINT GREEN (5475 2925);
DISPLAY INVISIBLE (5475 2925);
FORCEPROP 1 LAST COMMENT_BODY TRUE
J 0
(5275 2950);
DISPLAY 0.872340 (5275 2950);
PAINT GREEN (5275 2950);
DISPLAY INVISIBLE (5275 2950);
FORCEPROP 2 LAST PATH I221
J 0
(5200 3125);
DISPLAY 1.021277 (5200 3125);
PAINT ORANGE (5200 3125);
DISPLAY INVISIBLE (5200 3125);
FORCEADD GND..1
(6300 3450);
FORCEPROP 3 LASTPIN (6300 3500) SIG_NAME GND\g
J 0
(6310 3510);
DISPLAY 0.659574 (6310 3510);
PAINT MONO (6310 3510);
DISPLAY INVISIBLE (6310 3510);
FORCEPROP 2 LAST CDS_LIB mstr_symbols
J 0
(6300 3450);
PAINT ORANGE (6300 3450);
DISPLAY INVISIBLE (6300 3450);
FORCEPROP 1 LAST SIZE 1B
J 0
(6375 3400);
DISPLAY 0.872340 (6375 3400);
PAINT AQUA (6375 3400);
DISPLAY INVISIBLE (6375 3400);
FORCEPROP 1 LAST BODY_TYPE PLUMBING
J 0
(6255 3407);
DISPLAY 0.340426 (6255 3407);
PAINT GREEN (6255 3407);
DISPLAY INVISIBLE (6255 3407);
FORCEPROP 1 LAST PATH I223
J 0
(6375 3450);
DISPLAY 0.872340 (6375 3450);
PAINT AQUA (6375 3450);
DISPLAY INVISIBLE (6375 3450);
FORCEPROP 1 LAST HDL_POWER GND
J 0
(6300 3600);
DISPLAY 0.872340 (6300 3600);
PAINT GREEN (6300 3600);
DISPLAY INVISIBLE (6300 3600);
FORCEPROP 1 LAST VOLTAGE 0
J 0
(6300 3450);
PAINT SKYBLUE (6300 3450);
DISPLAY INVISIBLE (6300 3450);
FORCEADD OFFPAGE..1
(6825 3150);
FORCEPROP 2 LAST $XR0 101 
J 0
(6543 3150);
DISPLAY 0.638298 (6543 3150);
PAINT MONO (6543 3150);
FORCEPROP 2 LAST CDS_LIB mstr_standard
J 0
(6825 3150);
PAINT ORANGE (6825 3150);
DISPLAY INVISIBLE (6825 3150);
FORCEPROP 1 LAST OFFPAGE TRUE
J 0
(7150 3025);
DISPLAY 0.872340 (7150 3025);
PAINT GREEN (7150 3025);
DISPLAY INVISIBLE (7150 3025);
FORCEPROP 1 LAST COMMENT_BODY TRUE
J 0
(6950 3050);
DISPLAY 0.872340 (6950 3050);
PAINT GREEN (6950 3050);
DISPLAY INVISIBLE (6950 3050);
FORCEPROP 2 LAST PATH I227
J 0
(6875 3225);
DISPLAY 1.021277 (6875 3225);
PAINT ORANGE (6875 3225);
DISPLAY INVISIBLE (6875 3225);
FORCEADD OFFPAGE..1
(6825 3100);
FORCEPROP 2 LAST $XR1 150 
J 0
(6423 3100);
DISPLAY 0.638298 (6423 3100);
PAINT MONO (6423 3100);
FORCEPROP 2 LAST $XR0 147 
J 0
(6543 3100);
DISPLAY 0.638298 (6543 3100);
PAINT MONO (6543 3100);
FORCEPROP 2 LAST CDS_LIB mstr_standard
J 0
(6825 3100);
PAINT ORANGE (6825 3100);
DISPLAY INVISIBLE (6825 3100);
FORCEPROP 1 LAST OFFPAGE TRUE
J 0
(7150 2975);
DISPLAY 0.872340 (7150 2975);
PAINT GREEN (7150 2975);
DISPLAY INVISIBLE (7150 2975);
FORCEPROP 1 LAST COMMENT_BODY TRUE
J 0
(6950 3000);
DISPLAY 0.872340 (6950 3000);
PAINT GREEN (6950 3000);
DISPLAY INVISIBLE (6950 3000);
FORCEPROP 2 LAST PATH I228
J 0
(6875 3175);
DISPLAY 1.021277 (6875 3175);
PAINT ORANGE (6875 3175);
DISPLAY INVISIBLE (6875 3175);
FORCEADD OFFPAGE..1
(6825 3000);
FORCEPROP 2 LAST $XR1 185 
J 0
(6423 3000);
DISPLAY 0.638298 (6423 3000);
PAINT MONO (6423 3000);
FORCEPROP 2 LAST $XR0 159 
J 0
(6543 3000);
DISPLAY 0.638298 (6543 3000);
PAINT MONO (6543 3000);
FORCEPROP 2 LAST CDS_LIB mstr_standard
J 0
(6825 3000);
PAINT ORANGE (6825 3000);
DISPLAY INVISIBLE (6825 3000);
FORCEPROP 1 LAST OFFPAGE TRUE
J 0
(7150 2875);
DISPLAY 0.872340 (7150 2875);
PAINT GREEN (7150 2875);
DISPLAY INVISIBLE (7150 2875);
FORCEPROP 1 LAST COMMENT_BODY TRUE
J 0
(6950 2900);
DISPLAY 0.872340 (6950 2900);
PAINT GREEN (6950 2900);
DISPLAY INVISIBLE (6950 2900);
FORCEPROP 2 LAST PATH I229
J 0
(6875 3075);
DISPLAY 1.021277 (6875 3075);
PAINT ORANGE (6875 3075);
DISPLAY INVISIBLE (6875 3075);
FORCEADD OFFPAGE..1
(6825 2600);
FORCEPROP 2 LAST $XR0 114 
J 0
(6543 2600);
DISPLAY 0.638298 (6543 2600);
PAINT MONO (6543 2600);
FORCEPROP 2 LAST PATH I233
J 0
(6875 2675);
DISPLAY 1.021277 (6875 2675);
PAINT ORANGE (6875 2675);
DISPLAY INVISIBLE (6875 2675);
FORCEPROP 1 LAST COMMENT_BODY TRUE
J 0
(6950 2500);
DISPLAY 0.872340 (6950 2500);
PAINT GREEN (6950 2500);
DISPLAY INVISIBLE (6950 2500);
FORCEPROP 1 LAST OFFPAGE TRUE
J 0
(7150 2475);
DISPLAY 0.872340 (7150 2475);
PAINT GREEN (7150 2475);
DISPLAY INVISIBLE (7150 2475);
FORCEPROP 2 LAST CDS_LIB mstr_standard
J 0
(6825 2600);
PAINT ORANGE (6825 2600);
DISPLAY INVISIBLE (6825 2600);
FORCEADD OFFPAGE..1
(6825 2550);
FORCEPROP 2 LAST $XR0 114 
J 0
(6543 2550);
DISPLAY 0.638298 (6543 2550);
PAINT MONO (6543 2550);
FORCEPROP 2 LAST CDS_LIB mstr_standard
J 0
(6825 2550);
PAINT ORANGE (6825 2550);
DISPLAY INVISIBLE (6825 2550);
FORCEPROP 1 LAST OFFPAGE TRUE
J 0
(7150 2425);
DISPLAY 0.872340 (7150 2425);
PAINT GREEN (7150 2425);
DISPLAY INVISIBLE (7150 2425);
FORCEPROP 1 LAST COMMENT_BODY TRUE
J 0
(6950 2450);
DISPLAY 0.872340 (6950 2450);
PAINT GREEN (6950 2450);
DISPLAY INVISIBLE (6950 2450);
FORCEPROP 2 LAST PATH I234
J 0
(6875 2625);
DISPLAY 1.021277 (6875 2625);
PAINT ORANGE (6875 2625);
DISPLAY INVISIBLE (6875 2625);
FORCEADD P3V3..1
(8850 4050);
FORCEPROP 3 LASTPIN (8850 4000) SIG_NAME P3V3\g
J 0
(8860 4010);
DISPLAY 0.659574 (8860 4010);
PAINT MONO (8860 4010);
DISPLAY INVISIBLE (8860 4010);
FORCEPROP 1 LAST VOLTAGE +3.3
J 0
(8850 4050);
PAINT SKYBLUE (8850 4050);
DISPLAY INVISIBLE (8850 4050);
FORCEPROP 1 LAST HDL_POWER P3V3
J 0
(8525 3925);
DISPLAY 1.170213 (8525 3925);
PAINT GREEN (8525 3925);
DISPLAY INVISIBLE (8525 3925);
FORCEPROP 1 LAST PATH I247
J 0
(8895 4052);
DISPLAY 0.340426 (8895 4052);
PAINT GREEN (8895 4052);
DISPLAY INVISIBLE (8895 4052);
FORCEPROP 1 LAST BODY_TYPE PLUMBING
J 0
(8805 4007);
DISPLAY 0.468085 (8805 4007);
PAINT GREEN (8805 4007);
DISPLAY INVISIBLE (8805 4007);
FORCEPROP 1 LAST SIZE 1B
J 0
(8895 4072);
DISPLAY 0.468085 (8895 4072);
PAINT GREEN (8895 4072);
DISPLAY INVISIBLE (8895 4072);
FORCEPROP 2 LAST CDS_LIB mstr_symbols
J 0
(8850 4050);
PAINT ORANGE (8850 4050);
DISPLAY INVISIBLE (8850 4050);
FORCEADD OFFPAGE..3
R 2
(6825 2950);
FORCEPROP 2 LAST $XR1 185 
J 0
(6425 2950);
DISPLAY 0.638298 (6425 2950);
PAINT MONO (6425 2950);
FORCEPROP 2 LAST $XR0 159 
J 0
(6545 2950);
DISPLAY 0.638298 (6545 2950);
PAINT MONO (6545 2950);
FORCEPROP 2 LAST CDS_LIB mstr_standard
J 2
(6825 2950);
PAINT ORANGE (6825 2950);
DISPLAY INVISIBLE (6825 2950);
FORCEPROP 1 LAST OFFPAGE TRUE
J 2
(6500 2825);
DISPLAY 0.872340 (6500 2825);
PAINT GREEN (6500 2825);
DISPLAY INVISIBLE (6500 2825);
FORCEPROP 1 LAST COMMENT_BODY TRUE
J 2
(6875 2850);
DISPLAY 0.872340 (6875 2850);
PAINT GREEN (6875 2850);
DISPLAY INVISIBLE (6875 2850);
FORCEPROP 2 LAST PATH I249
J 2
(6625 3025);
DISPLAY 1.021277 (6625 3025);
PAINT ORANGE (6625 3025);
DISPLAY INVISIBLE (6625 3025);
FORCEADD OFFPAGE..1
R 2
(9750 3150);
FORCEPROP 2 LAST $XR3 188 
J 0
(10266 3150);
DISPLAY 0.638298 (10266 3150);
PAINT MONO (10266 3150);
FORCEPROP 2 LAST $XR2 91 
J 0
(10176 3150);
DISPLAY 0.638298 (10176 3150);
PAINT MONO (10176 3150);
FORCEPROP 2 LAST $XR1 159 
J 0
(10056 3150);
DISPLAY 0.638298 (10056 3150);
PAINT MONO (10056 3150);
FORCEPROP 2 LAST $XR0 138 
J 0
(9936 3150);
DISPLAY 0.638298 (9936 3150);
PAINT MONO (9936 3150);
FORCEPROP 2 LAST CDS_LIB mstr_standard
J 0
(9750 3150);
PAINT ORANGE (9750 3150);
DISPLAY INVISIBLE (9750 3150);
FORCEPROP 1 LAST OFFPAGE TRUE
J 2
(9425 3025);
DISPLAY 0.872340 (9425 3025);
PAINT GREEN (9425 3025);
DISPLAY INVISIBLE (9425 3025);
FORCEPROP 1 LAST COMMENT_BODY TRUE
J 2
(9625 3050);
DISPLAY 0.872340 (9625 3050);
PAINT GREEN (9625 3050);
DISPLAY INVISIBLE (9625 3050);
FORCEPROP 2 LAST PATH I250
J 0
(9925 3225);
DISPLAY 1.021277 (9925 3225);
PAINT ORANGE (9925 3225);
DISPLAY INVISIBLE (9925 3225);
FORCEADD OFFPAGE..2
(9750 3200);
FORCEPROP 2 LAST $XR3 145 
J 0
(10299 3200);
DISPLAY 0.638298 (10299 3200);
PAINT MONO (10299 3200);
FORCEPROP 2 LAST $XR2 119 
J 0
(10179 3200);
DISPLAY 0.638298 (10179 3200);
PAINT MONO (10179 3200);
FORCEPROP 2 LAST $XR1 185 
J 0
(10059 3200);
DISPLAY 0.638298 (10059 3200);
PAINT MONO (10059 3200);
FORCEPROP 2 LAST $XR0 157 
J 0
(9939 3200);
DISPLAY 0.638298 (9939 3200);
PAINT MONO (9939 3200);
FORCEPROP 2 LAST CDS_LIB mstr_standard
J 2
(9750 3200);
PAINT ORANGE (9750 3200);
DISPLAY INVISIBLE (9750 3200);
FORCEPROP 1 LAST OFFPAGE TRUE
J 0
(10075 3075);
DISPLAY 0.872340 (10075 3075);
PAINT GREEN (10075 3075);
DISPLAY INVISIBLE (10075 3075);
FORCEPROP 1 LAST COMMENT_BODY TRUE
J 0
(9705 3105);
DISPLAY 0.872340 (9705 3105);
PAINT GREEN (9705 3105);
DISPLAY INVISIBLE (9705 3105);
FORCEPROP 2 LAST PATH I251
J 2
(9575 3275);
DISPLAY 1.021277 (9575 3275);
PAINT ORANGE (9575 3275);
DISPLAY INVISIBLE (9575 3275);
FORCEADD OFFPAGE..2
(9750 3050);
FORCEPROP 2 LAST $XR0 142 
J 0
(9969 3050);
DISPLAY 0.638298 (9969 3050);
PAINT MONO (9969 3050);
FORCEPROP 2 LAST CDS_LIB mstr_standard
J 0
(9750 3050);
PAINT ORANGE (9750 3050);
DISPLAY INVISIBLE (9750 3050);
FORCEPROP 1 LAST OFFPAGE TRUE
J 0
(10075 2925);
DISPLAY 0.872340 (10075 2925);
PAINT GREEN (10075 2925);
DISPLAY INVISIBLE (10075 2925);
FORCEPROP 1 LAST COMMENT_BODY TRUE
J 0
(9705 2955);
DISPLAY 0.872340 (9705 2955);
PAINT GREEN (9705 2955);
DISPLAY INVISIBLE (9705 2955);
FORCEPROP 2 LAST PATH I252
J 0
(9925 3125);
DISPLAY 1.021277 (9925 3125);
PAINT ORANGE (9925 3125);
DISPLAY INVISIBLE (9925 3125);
FORCEADD OFFPAGE..1
R 2
(9750 2900);
FORCEPROP 2 LAST $XR0 147 
J 0
(9936 2900);
DISPLAY 0.638298 (9936 2900);
PAINT MONO (9936 2900);
FORCEPROP 2 LAST CDS_LIB mstr_standard
J 0
(9750 2900);
PAINT ORANGE (9750 2900);
DISPLAY INVISIBLE (9750 2900);
FORCEPROP 1 LAST OFFPAGE TRUE
J 2
(9425 2775);
DISPLAY 0.872340 (9425 2775);
PAINT GREEN (9425 2775);
DISPLAY INVISIBLE (9425 2775);
FORCEPROP 1 LAST COMMENT_BODY TRUE
J 2
(9625 2800);
DISPLAY 0.872340 (9625 2800);
PAINT GREEN (9625 2800);
DISPLAY INVISIBLE (9625 2800);
FORCEPROP 2 LAST PATH I254
J 0
(9925 2975);
DISPLAY 1.021277 (9925 2975);
PAINT ORANGE (9925 2975);
DISPLAY INVISIBLE (9925 2975);
FORCEADD OFFPAGE..1
R 2
(9750 2850);
FORCEPROP 2 LAST $XR0 147 
J 0
(9936 2850);
DISPLAY 0.638298 (9936 2850);
PAINT MONO (9936 2850);
FORCEPROP 2 LAST CDS_LIB mstr_standard
J 0
(9750 2850);
PAINT ORANGE (9750 2850);
DISPLAY INVISIBLE (9750 2850);
FORCEPROP 1 LAST OFFPAGE TRUE
J 2
(9425 2725);
DISPLAY 0.872340 (9425 2725);
PAINT GREEN (9425 2725);
DISPLAY INVISIBLE (9425 2725);
FORCEPROP 1 LAST COMMENT_BODY TRUE
J 2
(9625 2750);
DISPLAY 0.872340 (9625 2750);
PAINT GREEN (9625 2750);
DISPLAY INVISIBLE (9625 2750);
FORCEPROP 2 LAST PATH I255
J 0
(9925 2925);
DISPLAY 1.021277 (9925 2925);
PAINT ORANGE (9925 2925);
DISPLAY INVISIBLE (9925 2925);
FORCEADD OFFPAGE..1
R 2
(9750 2700);
FORCEPROP 2 LAST $XR0 114 
J 0
(9936 2700);
DISPLAY 0.638298 (9936 2700);
PAINT MONO (9936 2700);
FORCEPROP 2 LAST CDS_LIB mstr_standard
J 0
(9750 2700);
PAINT ORANGE (9750 2700);
DISPLAY INVISIBLE (9750 2700);
FORCEPROP 1 LAST OFFPAGE TRUE
J 2
(9425 2575);
DISPLAY 0.872340 (9425 2575);
PAINT GREEN (9425 2575);
DISPLAY INVISIBLE (9425 2575);
FORCEPROP 1 LAST COMMENT_BODY TRUE
J 2
(9625 2600);
DISPLAY 0.872340 (9625 2600);
PAINT GREEN (9625 2600);
DISPLAY INVISIBLE (9625 2600);
FORCEPROP 2 LAST PATH I256
J 0
(9925 2775);
DISPLAY 1.021277 (9925 2775);
PAINT ORANGE (9925 2775);
DISPLAY INVISIBLE (9925 2775);
FORCEADD OFFPAGE..1
R 2
(9750 2650);
FORCEPROP 2 LAST $XR0 114 
J 0
(9936 2650);
DISPLAY 0.638298 (9936 2650);
PAINT MONO (9936 2650);
FORCEPROP 2 LAST CDS_LIB mstr_standard
J 0
(9750 2650);
PAINT ORANGE (9750 2650);
DISPLAY INVISIBLE (9750 2650);
FORCEPROP 1 LAST OFFPAGE TRUE
J 2
(9425 2525);
DISPLAY 0.872340 (9425 2525);
PAINT GREEN (9425 2525);
DISPLAY INVISIBLE (9425 2525);
FORCEPROP 1 LAST COMMENT_BODY TRUE
J 2
(9625 2550);
DISPLAY 0.872340 (9625 2550);
PAINT GREEN (9625 2550);
DISPLAY INVISIBLE (9625 2550);
FORCEPROP 2 LAST PATH I257
J 0
(9925 2725);
DISPLAY 1.021277 (9925 2725);
PAINT ORANGE (9925 2725);
DISPLAY INVISIBLE (9925 2725);
FORCEADD P3V3..1
(10450 4950);
FORCEPROP 3 LASTPIN (10450 4900) SIG_NAME P3V3\g
J 0
(10460 4910);
DISPLAY 0.659574 (10460 4910);
PAINT MONO (10460 4910);
DISPLAY INVISIBLE (10460 4910);
FORCEPROP 1 LAST VOLTAGE +3.3
J 0
(10450 4950);
PAINT SKYBLUE (10450 4950);
DISPLAY INVISIBLE (10450 4950);
FORCEPROP 1 LAST HDL_POWER P3V3
J 0
(10125 4825);
DISPLAY 1.170213 (10125 4825);
PAINT GREEN (10125 4825);
DISPLAY INVISIBLE (10125 4825);
FORCEPROP 1 LAST PATH I268
J 0
(10495 4952);
DISPLAY 0.340426 (10495 4952);
PAINT GREEN (10495 4952);
DISPLAY INVISIBLE (10495 4952);
FORCEPROP 1 LAST BODY_TYPE PLUMBING
J 0
(10405 4907);
DISPLAY 0.468085 (10405 4907);
PAINT GREEN (10405 4907);
DISPLAY INVISIBLE (10405 4907);
FORCEPROP 2 LAST CDS_LIB mstr_symbols
J 0
(10450 4950);
PAINT ORANGE (10450 4950);
DISPLAY INVISIBLE (10450 4950);
FORCEPROP 1 LAST SIZE 1B
J 0
(10495 4972);
DISPLAY 0.468085 (10495 4972);
PAINT GREEN (10495 4972);
DISPLAY INVISIBLE (10495 4972);
FORCEADD GND..1
(11650 4275);
FORCEPROP 3 LASTPIN (11650 4325) SIG_NAME GND\g
J 0
(11660 4335);
DISPLAY 0.659574 (11660 4335);
PAINT MONO (11660 4335);
DISPLAY INVISIBLE (11660 4335);
FORCEPROP 1 LAST VOLTAGE 0
J 0
(11650 4275);
PAINT SKYBLUE (11650 4275);
DISPLAY INVISIBLE (11650 4275);
FORCEPROP 1 LAST HDL_POWER GND
J 0
(11650 4425);
DISPLAY 0.872340 (11650 4425);
PAINT GREEN (11650 4425);
DISPLAY INVISIBLE (11650 4425);
FORCEPROP 1 LAST SIZE 1B
J 0
(11725 4225);
DISPLAY 0.872340 (11725 4225);
PAINT AQUA (11725 4225);
DISPLAY INVISIBLE (11725 4225);
FORCEPROP 1 LAST BODY_TYPE PLUMBING
J 0
(11605 4232);
DISPLAY 0.340426 (11605 4232);
PAINT GREEN (11605 4232);
DISPLAY INVISIBLE (11605 4232);
FORCEPROP 1 LAST PATH I269
J 0
(11725 4275);
DISPLAY 0.872340 (11725 4275);
PAINT AQUA (11725 4275);
DISPLAY INVISIBLE (11725 4275);
FORCEPROP 2 LAST CDS_LIB mstr_symbols
J 0
(11650 4275);
PAINT ORANGE (11650 4275);
DISPLAY INVISIBLE (11650 4275);
FORCEADD CAP_A..1
(11650 4675);
FORCEPROP 1 LAST VALUE 0.1UF
J 0
(11700 4725);
DISPLAY 0.617021 (11700 4725);
PAINT SKYBLUE (11700 4725);
FORCEPROP 1 LAST TOLERANCE 10%
J 0
(11700 4625);
DISPLAY 0.617021 (11700 4625);
PAINT SKYBLUE (11700 4625);
FORCEPROP 1 LAST VOLTAGE 16V
J 0
(11700 4675);
DISPLAY 0.617021 (11700 4675);
PAINT SKYBLUE (11700 4675);
FORCEPROP 1 LAST LOCATION C1M20
J 0
(11700 4775);
DISPLAY 0.617021 (11700 4775);
PAINT AQUA (11700 4775);
FORCEPROP 1 LAST PACK_TYPE 0402V
J 0
(11700 4475);
DISPLAY 0.617021 (11700 4475);
PAINT SKYBLUE (11700 4475);
FORCEPROP 1 LASTPIN (11650 4775) $PN 1
J 0
(11660 4755);
DISPLAY 0.787234 (11660 4755);
PAINT ORANGE (11660 4755);
FORCEPROP 1 LAST PART_NUMBER A36096-030
J 0
(11700 4525);
DISPLAY 0.617021 (11700 4525);
PAINT BLUE (11700 4525);
FORCEPROP 1 LAST MATERIAL X7R
J 0
(11700 4575);
DISPLAY 0.617021 (11700 4575);
PAINT SKYBLUE (11700 4575);
FORCEPROP 1 LASTPIN (11650 4575) $PN 2
J 0
(11660 4555);
DISPLAY 0.787234 (11660 4555);
PAINT ORANGE (11660 4555);
FORCEPROP 0 LAST ROOM IO_SLOT
J 0
(11700 4875);
DISPLAY 1.021277 (11700 4875);
PAINT ORANGE (11700 4875);
DISPLAY INVISIBLE (11700 4875);
FORCEPROP 1 LAST PATH I270
J 0
(11700 4825);
DISPLAY 0.978723 (11700 4825);
PAINT WHITE (11700 4825);
DISPLAY INVISIBLE (11700 4825);
FORCEPROP 2 LAST CDS_LOCATION C1M20
J 0
(11700 4775);
DISPLAY 0.617021 (11700 4775);
PAINT AQUA (11700 4775);
DISPLAY INVISIBLE (11700 4775);
FORCEPROP 2 LAST CDS_LIB dev_discrete
J 0
(11650 4675);
PAINT ORANGE (11650 4675);
DISPLAY INVISIBLE (11650 4675);
FORCEPROP 2 LAST SEC 1
J 0
(11700 4875);
DISPLAY 0.680851 (11700 4875);
PAINT MONO (11700 4875);
DISPLAY INVISIBLE (11700 4875);
FORCEPROP 2 LAST SEC_TYPE 0402V
J 0
(11700 4875);
DISPLAY 1.021277 (11700 4875);
PAINT ORANGE (11700 4875);
DISPLAY INVISIBLE (11700 4875);
FORCEADD P3V3_STBY..1
(7375 4025);
FORCEPROP 3 LASTPIN (7375 3975) SIG_NAME P3V3_STBY\g
J 0
(7385 3985);
DISPLAY 0.659574 (7385 3985);
PAINT MONO (7385 3985);
DISPLAY INVISIBLE (7385 3985);
FORCEPROP 1 LAST VOLTAGE 3.3V
J 0
(7330 3982);
DISPLAY 0.340426 (7330 3982);
PAINT SKYBLUE (7330 3982);
DISPLAY INVISIBLE (7330 3982);
FORCEPROP 1 LAST HDL_POWER P3V3_STBY
J 0
(7075 3900);
DISPLAY 0.872340 (7075 3900);
PAINT ORANGE (7075 3900);
DISPLAY INVISIBLE (7075 3900);
FORCEPROP 1 LAST BODY_TYPE PLUMBING
J 0
(7330 3982);
DISPLAY 0.340426 (7330 3982);
PAINT GREEN (7330 3982);
DISPLAY INVISIBLE (7330 3982);
FORCEPROP 1 LAST SIZE 1B
J 0
(7420 4047);
DISPLAY 0.340426 (7420 4047);
PAINT GREEN (7420 4047);
DISPLAY INVISIBLE (7420 4047);
FORCEPROP 1 LAST PATH I274
J 0
(7420 4027);
DISPLAY 0.340426 (7420 4027);
PAINT GREEN (7420 4027);
DISPLAY INVISIBLE (7420 4027);
FORCEPROP 2 LAST CDS_LIB mstr_symbols
J 0
(7375 4025);
PAINT ORANGE (7375 4025);
DISPLAY INVISIBLE (7375 4025);
FORCEADD P3V3_STBY..1
(8725 4200);
FORCEPROP 3 LASTPIN (8725 4150) SIG_NAME P3V3_STBY\g
J 0
(8735 4160);
DISPLAY 0.659574 (8735 4160);
PAINT MONO (8735 4160);
DISPLAY INVISIBLE (8735 4160);
FORCEPROP 1 LAST VOLTAGE 3.3V
J 0
(8680 4157);
DISPLAY 0.340426 (8680 4157);
PAINT SKYBLUE (8680 4157);
DISPLAY INVISIBLE (8680 4157);
FORCEPROP 1 LAST HDL_POWER P3V3_STBY
J 0
(8425 4075);
DISPLAY 0.872340 (8425 4075);
PAINT ORANGE (8425 4075);
DISPLAY INVISIBLE (8425 4075);
FORCEPROP 1 LAST PATH I275
J 0
(8770 4202);
DISPLAY 0.340426 (8770 4202);
PAINT GREEN (8770 4202);
DISPLAY INVISIBLE (8770 4202);
FORCEPROP 1 LAST BODY_TYPE PLUMBING
J 0
(8680 4157);
DISPLAY 0.340426 (8680 4157);
PAINT GREEN (8680 4157);
DISPLAY INVISIBLE (8680 4157);
FORCEPROP 2 LAST CDS_LIB mstr_symbols
J 0
(8725 4200);
PAINT ORANGE (8725 4200);
DISPLAY INVISIBLE (8725 4200);
FORCEPROP 1 LAST SIZE 1B
J 0
(8770 4222);
DISPLAY 0.340426 (8770 4222);
PAINT GREEN (8770 4222);
DISPLAY INVISIBLE (8770 4222);
FORCEADD P5V_STBY..1
(7650 4050);
FORCEPROP 3 LASTPIN (7650 4000) SIG_NAME P5V_STBY\g
J 0
(7660 4010);
DISPLAY 0.659574 (7660 4010);
PAINT MONO (7660 4010);
DISPLAY INVISIBLE (7660 4010);
FORCEPROP 1 LAST VOLTAGE 5.0V
J 0
(7605 4007);
DISPLAY 0.340426 (7605 4007);
PAINT SKYBLUE (7605 4007);
DISPLAY INVISIBLE (7605 4007);
FORCEPROP 1 LAST HDL_POWER P5V_STBY
J 0
(7350 3925);
DISPLAY 0.872340 (7350 3925);
PAINT ORANGE (7350 3925);
DISPLAY INVISIBLE (7350 3925);
FORCEPROP 1 LAST SIZE 1B
J 0
(7695 4072);
DISPLAY 0.340426 (7695 4072);
PAINT GREEN (7695 4072);
DISPLAY INVISIBLE (7695 4072);
FORCEPROP 1 LAST BODY_TYPE PLUMBING
J 0
(7605 4007);
DISPLAY 0.340426 (7605 4007);
PAINT GREEN (7605 4007);
DISPLAY INVISIBLE (7605 4007);
FORCEPROP 1 LAST PATH I276
J 0
(7695 4052);
DISPLAY 0.340426 (7695 4052);
PAINT GREEN (7695 4052);
DISPLAY INVISIBLE (7695 4052);
FORCEPROP 2 LAST CDS_LIB mstr_symbols
J 0
(7650 4050);
PAINT ORANGE (7650 4050);
DISPLAY INVISIBLE (7650 4050);
FORCEADD P12V_STBY..1
(9200 4225);
FORCEPROP 3 LASTPIN (9200 4175) SIG_NAME P12V_STBY\g
J 0
(9210 4185);
DISPLAY 0.659574 (9210 4185);
PAINT MONO (9210 4185);
DISPLAY INVISIBLE (9210 4185);
FORCEPROP 1 LAST SIZE 1B
J 0
(9245 4247);
DISPLAY 0.340426 (9245 4247);
PAINT GREEN (9245 4247);
DISPLAY INVISIBLE (9245 4247);
FORCEPROP 2 LAST CDS_LIB mstr_symbols
J 0
(9200 4225);
PAINT ORANGE (9200 4225);
DISPLAY INVISIBLE (9200 4225);
FORCEPROP 1 LAST BODY_TYPE PLUMBING
J 0
(9155 4182);
DISPLAY 0.340426 (9155 4182);
PAINT GREEN (9155 4182);
DISPLAY INVISIBLE (9155 4182);
FORCEPROP 1 LAST PATH I278
J 0
(9245 4227);
DISPLAY 0.340426 (9245 4227);
PAINT GREEN (9245 4227);
DISPLAY INVISIBLE (9245 4227);
FORCEPROP 1 LAST HDL_POWER P12V_STBY
J 0
(8900 4100);
DISPLAY 0.872340 (8900 4100);
PAINT ORANGE (8900 4100);
DISPLAY INVISIBLE (8900 4100);
FORCEPROP 1 LAST VOLTAGE 12.0V
J 0
(9155 4182);
DISPLAY 0.340426 (9155 4182);
PAINT SKYBLUE (9155 4182);
DISPLAY INVISIBLE (9155 4182);
FORCEADD P12V_STBY..1
(10450 4225);
FORCEPROP 3 LASTPIN (10450 4175) SIG_NAME P12V_STBY\g
J 0
(10460 4185);
DISPLAY 0.659574 (10460 4185);
PAINT MONO (10460 4185);
DISPLAY INVISIBLE (10460 4185);
FORCEPROP 1 LAST VOLTAGE 12.0V
J 0
(10405 4182);
DISPLAY 0.340426 (10405 4182);
PAINT SKYBLUE (10405 4182);
DISPLAY INVISIBLE (10405 4182);
FORCEPROP 1 LAST HDL_POWER P12V_STBY
J 0
(10150 4100);
DISPLAY 0.872340 (10150 4100);
PAINT ORANGE (10150 4100);
DISPLAY INVISIBLE (10150 4100);
FORCEPROP 1 LAST PATH I279
J 0
(10495 4227);
DISPLAY 0.340426 (10495 4227);
PAINT GREEN (10495 4227);
DISPLAY INVISIBLE (10495 4227);
FORCEPROP 1 LAST BODY_TYPE PLUMBING
J 0
(10405 4182);
DISPLAY 0.340426 (10405 4182);
PAINT GREEN (10405 4182);
DISPLAY INVISIBLE (10405 4182);
FORCEPROP 2 LAST CDS_LIB mstr_symbols
J 0
(10450 4225);
PAINT ORANGE (10450 4225);
DISPLAY INVISIBLE (10450 4225);
FORCEPROP 1 LAST SIZE 1B
J 0
(10495 4247);
DISPLAY 0.340426 (10495 4247);
PAINT GREEN (10495 4247);
DISPLAY INVISIBLE (10495 4247);
FORCEADD P3V3_STBY..1
(11250 4950);
FORCEPROP 3 LASTPIN (11250 4900) SIG_NAME P3V3_STBY\g
J 0
(11260 4910);
DISPLAY 0.659574 (11260 4910);
PAINT MONO (11260 4910);
DISPLAY INVISIBLE (11260 4910);
FORCEPROP 1 LAST VOLTAGE 3.3V
J 0
(11205 4907);
DISPLAY 0.340426 (11205 4907);
PAINT SKYBLUE (11205 4907);
DISPLAY INVISIBLE (11205 4907);
FORCEPROP 1 LAST HDL_POWER P3V3_STBY
J 0
(10950 4825);
DISPLAY 0.872340 (10950 4825);
PAINT ORANGE (10950 4825);
DISPLAY INVISIBLE (10950 4825);
FORCEPROP 1 LAST PATH I296
J 0
(11295 4952);
DISPLAY 0.340426 (11295 4952);
PAINT GREEN (11295 4952);
DISPLAY INVISIBLE (11295 4952);
FORCEPROP 1 LAST BODY_TYPE PLUMBING
J 0
(11205 4907);
DISPLAY 0.340426 (11205 4907);
PAINT GREEN (11205 4907);
DISPLAY INVISIBLE (11205 4907);
FORCEPROP 2 LAST CDS_LIB mstr_symbols
J 0
(11250 4950);
PAINT ORANGE (11250 4950);
DISPLAY INVISIBLE (11250 4950);
FORCEPROP 1 LAST SIZE 1B
J 0
(11295 4972);
DISPLAY 0.340426 (11295 4972);
PAINT GREEN (11295 4972);
DISPLAY INVISIBLE (11295 4972);
FORCEADD TAP..1
R 2
(6250 1750);
FORCEPROP 3 LASTPIN (6300 1750) SIG_NAME P3E_CPU0_PE3_OCP_RXN<12>
J 0
(6310 1760);
DISPLAY 0.659574 (6310 1760);
PAINT MONO (6310 1760);
DISPLAY INVISIBLE (6310 1760);
FORCEPROP 1 LASTPIN (6300 1750) BN 12
J 2
(6312 1758);
DISPLAY 0.617021 (6312 1758);
PAINT GREEN (6312 1758);
FORCEPROP 1 LAST PATH I297
J 2
(6252 1750);
DISPLAY 0.872340 (6252 1750);
PAINT GREEN (6252 1750);
DISPLAY INVISIBLE (6252 1750);
FORCEPROP 1 LAST HDL_TAP TRUE
J 2
(5925 1625);
DISPLAY 0.872340 (5925 1625);
PAINT ORANGE (5925 1625);
DISPLAY INVISIBLE (5925 1625);
FORCEPROP 1 LAST BODY_TYPE PLUMBING
J 2
(6250 1800);
DISPLAY 0.872340 (6250 1800);
PAINT GREEN (6250 1800);
DISPLAY INVISIBLE (6250 1800);
FORCEPROP 2 LAST CDS_LIB mstr_standard
J 0
(6250 1750);
PAINT ORANGE (6250 1750);
DISPLAY INVISIBLE (6250 1750);
FORCEADD TAP..1
R 2
(6250 1550);
FORCEPROP 3 LASTPIN (6300 1550) SIG_NAME P3E_CPU0_PE3_OCP_RXN<11>
J 0
(6310 1560);
DISPLAY 0.659574 (6310 1560);
PAINT MONO (6310 1560);
DISPLAY INVISIBLE (6310 1560);
FORCEPROP 1 LASTPIN (6300 1550) BN 11
J 2
(6312 1558);
DISPLAY 0.617021 (6312 1558);
PAINT GREEN (6312 1558);
FORCEPROP 1 LAST PATH I298
J 2
(6252 1550);
DISPLAY 0.872340 (6252 1550);
PAINT GREEN (6252 1550);
DISPLAY INVISIBLE (6252 1550);
FORCEPROP 1 LAST HDL_TAP TRUE
J 2
(5925 1425);
DISPLAY 0.872340 (5925 1425);
PAINT ORANGE (5925 1425);
DISPLAY INVISIBLE (5925 1425);
FORCEPROP 1 LAST BODY_TYPE PLUMBING
J 2
(6250 1600);
DISPLAY 0.872340 (6250 1600);
PAINT GREEN (6250 1600);
DISPLAY INVISIBLE (6250 1600);
FORCEPROP 2 LAST CDS_LIB mstr_standard
J 0
(6250 1550);
PAINT ORANGE (6250 1550);
DISPLAY INVISIBLE (6250 1550);
FORCEADD TAP..1
R 2
(6250 1350);
FORCEPROP 3 LASTPIN (6300 1350) SIG_NAME P3E_CPU0_PE3_OCP_RXN<10>
J 0
(6310 1360);
DISPLAY 0.659574 (6310 1360);
PAINT MONO (6310 1360);
DISPLAY INVISIBLE (6310 1360);
FORCEPROP 1 LASTPIN (6300 1350) BN 10
J 2
(6312 1358);
DISPLAY 0.617021 (6312 1358);
PAINT GREEN (6312 1358);
FORCEPROP 1 LAST PATH I299
J 2
(6252 1350);
DISPLAY 0.872340 (6252 1350);
PAINT GREEN (6252 1350);
DISPLAY INVISIBLE (6252 1350);
FORCEPROP 1 LAST HDL_TAP TRUE
J 2
(5925 1225);
DISPLAY 0.872340 (5925 1225);
PAINT ORANGE (5925 1225);
DISPLAY INVISIBLE (5925 1225);
FORCEPROP 1 LAST BODY_TYPE PLUMBING
J 2
(6250 1400);
DISPLAY 0.872340 (6250 1400);
PAINT GREEN (6250 1400);
DISPLAY INVISIBLE (6250 1400);
FORCEPROP 2 LAST CDS_LIB mstr_standard
J 0
(6250 1350);
PAINT ORANGE (6250 1350);
DISPLAY INVISIBLE (6250 1350);
FORCEADD CAP..1
(10450 3975);
FORCEPROP 1 LAST LOCATION C1M27
J 0
(10500 4075);
DISPLAY 0.617021 (10500 4075);
PAINT AQUA (10500 4075);
FORCEPROP 1 LASTPIN (10450 4075) $PN 1
J 0
(10460 4055);
DISPLAY 0.617021 (10460 4055);
PAINT ORANGE (10460 4055);
FORCEPROP 1 LAST VALUE 10UF
J 0
(10500 4025);
DISPLAY 0.617021 (10500 4025);
PAINT SKYBLUE (10500 4025);
FORCEPROP 1 LAST TOLERANCE 10%
J 0
(10500 3925);
DISPLAY 0.617021 (10500 3925);
PAINT SKYBLUE (10500 3925);
FORCEPROP 1 LAST VOLTAGE 16V
J 0
(10500 3975);
DISPLAY 0.617021 (10500 3975);
PAINT SKYBLUE (10500 3975);
FORCEPROP 1 LAST MATERIAL X6S
J 0
(10500 3875);
DISPLAY 0.617021 (10500 3875);
PAINT SKYBLUE (10500 3875);
FORCEPROP 1 LAST PACK_TYPE 0805
J 0
(10500 3775);
DISPLAY 0.617021 (10500 3775);
PAINT SKYBLUE (10500 3775);
FORCEPROP 1 LAST PART_NUMBER C95333-007
J 0
(10500 3825);
DISPLAY 0.617021 (10500 3825);
PAINT BLUE (10500 3825);
FORCEPROP 1 LASTPIN (10450 3875) $PN 2
J 0
(10460 3855);
DISPLAY 0.617021 (10460 3855);
PAINT ORANGE (10460 3855);
FORCEPROP 0 LAST ROOM IO_SLOT
J 0
(10500 4175);
DISPLAY 1.021277 (10500 4175);
PAINT ORANGE (10500 4175);
DISPLAY INVISIBLE (10500 4175);
FORCEPROP 1 LAST PATH I3
J 0
(10500 4125);
DISPLAY 0.978723 (10500 4125);
PAINT WHITE (10500 4125);
DISPLAY INVISIBLE (10500 4125);
FORCEPROP 2 LAST CDS_LOCATION C1M27
J 0
(10500 4075);
DISPLAY 0.617021 (10500 4075);
PAINT AQUA (10500 4075);
DISPLAY INVISIBLE (10500 4075);
FORCEPROP 2 LAST SEC 1
J 0
(10500 4175);
DISPLAY 0.680851 (10500 4175);
PAINT MONO (10500 4175);
DISPLAY INVISIBLE (10500 4175);
FORCEPROP 2 LAST CDS_LIB mstr_discrete
J 0
(10450 3975);
PAINT ORANGE (10450 3975);
DISPLAY INVISIBLE (10450 3975);
FORCEPROP 2 LAST SEC_TYPE 0805
J 0
(10500 4175);
DISPLAY 1.021277 (10500 4175);
PAINT ORANGE (10500 4175);
DISPLAY INVISIBLE (10500 4175);
FORCEADD TAP..1
R 2
(6425 1000);
FORCEPROP 3 LASTPIN (6475 1000) SIG_NAME P3E_CPU0_PE3_OCP_RXP<8>
J 0
(6485 1010);
DISPLAY 0.659574 (6485 1010);
PAINT MONO (6485 1010);
DISPLAY INVISIBLE (6485 1010);
FORCEPROP 1 LASTPIN (6475 1000) BN 8
J 2
(6487 1008);
DISPLAY 0.617021 (6487 1008);
PAINT GREEN (6487 1008);
FORCEPROP 1 LAST PATH I300
J 2
(6427 1000);
DISPLAY 0.872340 (6427 1000);
PAINT GREEN (6427 1000);
DISPLAY INVISIBLE (6427 1000);
FORCEPROP 1 LAST HDL_TAP TRUE
J 2
(6100 875);
DISPLAY 0.872340 (6100 875);
PAINT ORANGE (6100 875);
DISPLAY INVISIBLE (6100 875);
FORCEPROP 1 LAST BODY_TYPE PLUMBING
J 2
(6425 1050);
DISPLAY 0.872340 (6425 1050);
PAINT GREEN (6425 1050);
DISPLAY INVISIBLE (6425 1050);
FORCEPROP 2 LAST CDS_LIB mstr_standard
J 0
(6425 1000);
PAINT ORANGE (6425 1000);
DISPLAY INVISIBLE (6425 1000);
FORCEADD TAP..1
R 2
(6425 2200);
FORCEPROP 3 LASTPIN (6475 2200) SIG_NAME P3E_CPU0_PE3_OCP_RXP<14>
J 0
(6485 2210);
DISPLAY 0.659574 (6485 2210);
PAINT MONO (6485 2210);
DISPLAY INVISIBLE (6485 2210);
FORCEPROP 1 LASTPIN (6475 2200) BN 14
J 2
(6487 2208);
DISPLAY 0.617021 (6487 2208);
PAINT GREEN (6487 2208);
FORCEPROP 1 LAST PATH I301
J 2
(6427 2200);
DISPLAY 0.872340 (6427 2200);
PAINT GREEN (6427 2200);
DISPLAY INVISIBLE (6427 2200);
FORCEPROP 1 LAST HDL_TAP TRUE
J 2
(6100 2075);
DISPLAY 0.872340 (6100 2075);
PAINT ORANGE (6100 2075);
DISPLAY INVISIBLE (6100 2075);
FORCEPROP 1 LAST BODY_TYPE PLUMBING
J 2
(6425 2250);
DISPLAY 0.872340 (6425 2250);
PAINT GREEN (6425 2250);
DISPLAY INVISIBLE (6425 2250);
FORCEPROP 2 LAST CDS_LIB mstr_standard
J 0
(6425 2200);
PAINT ORANGE (6425 2200);
DISPLAY INVISIBLE (6425 2200);
FORCEADD TAP..1
R 2
(6425 2400);
FORCEPROP 3 LASTPIN (6475 2400) SIG_NAME P3E_CPU0_PE3_OCP_RXP<15>
J 0
(6485 2410);
DISPLAY 0.659574 (6485 2410);
PAINT MONO (6485 2410);
DISPLAY INVISIBLE (6485 2410);
FORCEPROP 1 LASTPIN (6475 2400) BN 15
J 2
(6487 2408);
DISPLAY 0.617021 (6487 2408);
PAINT GREEN (6487 2408);
FORCEPROP 1 LAST PATH I302
J 2
(6427 2400);
DISPLAY 0.872340 (6427 2400);
PAINT GREEN (6427 2400);
DISPLAY INVISIBLE (6427 2400);
FORCEPROP 1 LAST HDL_TAP TRUE
J 2
(6100 2275);
DISPLAY 0.872340 (6100 2275);
PAINT ORANGE (6100 2275);
DISPLAY INVISIBLE (6100 2275);
FORCEPROP 1 LAST BODY_TYPE PLUMBING
J 2
(6425 2450);
DISPLAY 0.872340 (6425 2450);
PAINT GREEN (6425 2450);
DISPLAY INVISIBLE (6425 2450);
FORCEPROP 2 LAST CDS_LIB mstr_standard
J 0
(6425 2400);
PAINT ORANGE (6425 2400);
DISPLAY INVISIBLE (6425 2400);
FORCEADD TAP..1
R 2
(6250 2350);
FORCEPROP 3 LASTPIN (6300 2350) SIG_NAME P3E_CPU0_PE3_OCP_RXN<15>
J 0
(6310 2360);
DISPLAY 0.659574 (6310 2360);
PAINT MONO (6310 2360);
DISPLAY INVISIBLE (6310 2360);
FORCEPROP 1 LASTPIN (6300 2350) BN 15
J 2
(6312 2358);
DISPLAY 0.617021 (6312 2358);
PAINT GREEN (6312 2358);
FORCEPROP 1 LAST PATH I303
J 2
(6252 2350);
DISPLAY 0.872340 (6252 2350);
PAINT GREEN (6252 2350);
DISPLAY INVISIBLE (6252 2350);
FORCEPROP 1 LAST HDL_TAP TRUE
J 2
(5925 2225);
DISPLAY 0.872340 (5925 2225);
PAINT ORANGE (5925 2225);
DISPLAY INVISIBLE (5925 2225);
FORCEPROP 1 LAST BODY_TYPE PLUMBING
J 2
(6250 2400);
DISPLAY 0.872340 (6250 2400);
PAINT GREEN (6250 2400);
DISPLAY INVISIBLE (6250 2400);
FORCEPROP 2 LAST CDS_LIB mstr_standard
J 0
(6250 2350);
PAINT ORANGE (6250 2350);
DISPLAY INVISIBLE (6250 2350);
FORCEADD TAP..1
R 2
(6425 2000);
FORCEPROP 3 LASTPIN (6475 2000) SIG_NAME P3E_CPU0_PE3_OCP_RXP<13>
J 0
(6485 2010);
DISPLAY 0.659574 (6485 2010);
PAINT MONO (6485 2010);
DISPLAY INVISIBLE (6485 2010);
FORCEPROP 1 LASTPIN (6475 2000) BN 13
J 2
(6487 2008);
DISPLAY 0.617021 (6487 2008);
PAINT GREEN (6487 2008);
FORCEPROP 1 LAST PATH I304
J 2
(6427 2000);
DISPLAY 0.872340 (6427 2000);
PAINT GREEN (6427 2000);
DISPLAY INVISIBLE (6427 2000);
FORCEPROP 1 LAST HDL_TAP TRUE
J 2
(6100 1875);
DISPLAY 0.872340 (6100 1875);
PAINT ORANGE (6100 1875);
DISPLAY INVISIBLE (6100 1875);
FORCEPROP 1 LAST BODY_TYPE PLUMBING
J 2
(6425 2050);
DISPLAY 0.872340 (6425 2050);
PAINT GREEN (6425 2050);
DISPLAY INVISIBLE (6425 2050);
FORCEPROP 2 LAST CDS_LIB mstr_standard
J 0
(6425 2000);
PAINT ORANGE (6425 2000);
DISPLAY INVISIBLE (6425 2000);
FORCEADD TAP..1
R 2
(6425 1800);
FORCEPROP 3 LASTPIN (6475 1800) SIG_NAME P3E_CPU0_PE3_OCP_RXP<12>
J 0
(6485 1810);
DISPLAY 0.659574 (6485 1810);
PAINT MONO (6485 1810);
DISPLAY INVISIBLE (6485 1810);
FORCEPROP 1 LASTPIN (6475 1800) BN 12
J 2
(6487 1808);
DISPLAY 0.617021 (6487 1808);
PAINT GREEN (6487 1808);
FORCEPROP 1 LAST PATH I305
J 2
(6427 1800);
DISPLAY 0.872340 (6427 1800);
PAINT GREEN (6427 1800);
DISPLAY INVISIBLE (6427 1800);
FORCEPROP 1 LAST HDL_TAP TRUE
J 2
(6100 1675);
DISPLAY 0.872340 (6100 1675);
PAINT ORANGE (6100 1675);
DISPLAY INVISIBLE (6100 1675);
FORCEPROP 1 LAST BODY_TYPE PLUMBING
J 2
(6425 1850);
DISPLAY 0.872340 (6425 1850);
PAINT GREEN (6425 1850);
DISPLAY INVISIBLE (6425 1850);
FORCEPROP 2 LAST CDS_LIB mstr_standard
J 0
(6425 1800);
PAINT ORANGE (6425 1800);
DISPLAY INVISIBLE (6425 1800);
FORCEADD TAP..1
R 2
(6250 2150);
FORCEPROP 3 LASTPIN (6300 2150) SIG_NAME P3E_CPU0_PE3_OCP_RXN<14>
J 0
(6310 2160);
DISPLAY 0.659574 (6310 2160);
PAINT MONO (6310 2160);
DISPLAY INVISIBLE (6310 2160);
FORCEPROP 1 LASTPIN (6300 2150) BN 14
J 2
(6312 2158);
DISPLAY 0.617021 (6312 2158);
PAINT GREEN (6312 2158);
FORCEPROP 1 LAST PATH I306
J 2
(6252 2150);
DISPLAY 0.872340 (6252 2150);
PAINT GREEN (6252 2150);
DISPLAY INVISIBLE (6252 2150);
FORCEPROP 1 LAST HDL_TAP TRUE
J 2
(5925 2025);
DISPLAY 0.872340 (5925 2025);
PAINT ORANGE (5925 2025);
DISPLAY INVISIBLE (5925 2025);
FORCEPROP 1 LAST BODY_TYPE PLUMBING
J 2
(6250 2200);
DISPLAY 0.872340 (6250 2200);
PAINT GREEN (6250 2200);
DISPLAY INVISIBLE (6250 2200);
FORCEPROP 2 LAST CDS_LIB mstr_standard
J 0
(6250 2150);
PAINT ORANGE (6250 2150);
DISPLAY INVISIBLE (6250 2150);
FORCEADD TAP..1
R 2
(6250 1950);
FORCEPROP 3 LASTPIN (6300 1950) SIG_NAME P3E_CPU0_PE3_OCP_RXN<13>
J 0
(6310 1960);
DISPLAY 0.659574 (6310 1960);
PAINT MONO (6310 1960);
DISPLAY INVISIBLE (6310 1960);
FORCEPROP 1 LASTPIN (6300 1950) BN 13
J 2
(6312 1958);
DISPLAY 0.617021 (6312 1958);
PAINT GREEN (6312 1958);
FORCEPROP 1 LAST PATH I307
J 2
(6252 1950);
DISPLAY 0.872340 (6252 1950);
PAINT GREEN (6252 1950);
DISPLAY INVISIBLE (6252 1950);
FORCEPROP 1 LAST HDL_TAP TRUE
J 2
(5925 1825);
DISPLAY 0.872340 (5925 1825);
PAINT ORANGE (5925 1825);
DISPLAY INVISIBLE (5925 1825);
FORCEPROP 1 LAST BODY_TYPE PLUMBING
J 2
(6250 2000);
DISPLAY 0.872340 (6250 2000);
PAINT GREEN (6250 2000);
DISPLAY INVISIBLE (6250 2000);
FORCEPROP 2 LAST CDS_LIB mstr_standard
J 0
(6250 1950);
PAINT ORANGE (6250 1950);
DISPLAY INVISIBLE (6250 1950);
FORCEADD TAP..1
R 2
(6425 1600);
FORCEPROP 3 LASTPIN (6475 1600) SIG_NAME P3E_CPU0_PE3_OCP_RXP<11>
J 0
(6485 1610);
DISPLAY 0.659574 (6485 1610);
PAINT MONO (6485 1610);
DISPLAY INVISIBLE (6485 1610);
FORCEPROP 1 LASTPIN (6475 1600) BN 11
J 2
(6487 1608);
DISPLAY 0.617021 (6487 1608);
PAINT GREEN (6487 1608);
FORCEPROP 1 LAST PATH I308
J 2
(6427 1600);
DISPLAY 0.872340 (6427 1600);
PAINT GREEN (6427 1600);
DISPLAY INVISIBLE (6427 1600);
FORCEPROP 1 LAST HDL_TAP TRUE
J 2
(6100 1475);
DISPLAY 0.872340 (6100 1475);
PAINT ORANGE (6100 1475);
DISPLAY INVISIBLE (6100 1475);
FORCEPROP 1 LAST BODY_TYPE PLUMBING
J 2
(6425 1650);
DISPLAY 0.872340 (6425 1650);
PAINT GREEN (6425 1650);
DISPLAY INVISIBLE (6425 1650);
FORCEPROP 2 LAST CDS_LIB mstr_standard
J 0
(6425 1600);
PAINT ORANGE (6425 1600);
DISPLAY INVISIBLE (6425 1600);
FORCEADD TAP..1
R 2
(6425 1400);
FORCEPROP 3 LASTPIN (6475 1400) SIG_NAME P3E_CPU0_PE3_OCP_RXP<10>
J 0
(6485 1410);
DISPLAY 0.659574 (6485 1410);
PAINT MONO (6485 1410);
DISPLAY INVISIBLE (6485 1410);
FORCEPROP 1 LASTPIN (6475 1400) BN 10
J 2
(6487 1408);
DISPLAY 0.617021 (6487 1408);
PAINT GREEN (6487 1408);
FORCEPROP 1 LAST PATH I309
J 2
(6427 1400);
DISPLAY 0.872340 (6427 1400);
PAINT GREEN (6427 1400);
DISPLAY INVISIBLE (6427 1400);
FORCEPROP 1 LAST HDL_TAP TRUE
J 2
(6100 1275);
DISPLAY 0.872340 (6100 1275);
PAINT ORANGE (6100 1275);
DISPLAY INVISIBLE (6100 1275);
FORCEPROP 1 LAST BODY_TYPE PLUMBING
J 2
(6425 1450);
DISPLAY 0.872340 (6425 1450);
PAINT GREEN (6425 1450);
DISPLAY INVISIBLE (6425 1450);
FORCEPROP 2 LAST CDS_LIB mstr_standard
J 0
(6425 1400);
PAINT ORANGE (6425 1400);
DISPLAY INVISIBLE (6425 1400);
FORCEADD TAP..1
R 2
(6425 1200);
FORCEPROP 3 LASTPIN (6475 1200) SIG_NAME P3E_CPU0_PE3_OCP_RXP<9>
J 0
(6485 1210);
DISPLAY 0.659574 (6485 1210);
PAINT MONO (6485 1210);
DISPLAY INVISIBLE (6485 1210);
FORCEPROP 1 LASTPIN (6475 1200) BN 9
J 2
(6487 1208);
DISPLAY 0.617021 (6487 1208);
PAINT GREEN (6487 1208);
FORCEPROP 1 LAST PATH I310
J 2
(6427 1200);
DISPLAY 0.872340 (6427 1200);
PAINT GREEN (6427 1200);
DISPLAY INVISIBLE (6427 1200);
FORCEPROP 1 LAST HDL_TAP TRUE
J 2
(6100 1075);
DISPLAY 0.872340 (6100 1075);
PAINT ORANGE (6100 1075);
DISPLAY INVISIBLE (6100 1075);
FORCEPROP 1 LAST BODY_TYPE PLUMBING
J 2
(6425 1250);
DISPLAY 0.872340 (6425 1250);
PAINT GREEN (6425 1250);
DISPLAY INVISIBLE (6425 1250);
FORCEPROP 2 LAST CDS_LIB mstr_standard
J 0
(6425 1200);
PAINT ORANGE (6425 1200);
DISPLAY INVISIBLE (6425 1200);
FORCEADD TAP..1
R 2
(6250 1150);
FORCEPROP 3 LASTPIN (6300 1150) SIG_NAME P3E_CPU0_PE3_OCP_RXN<9>
J 0
(6310 1160);
DISPLAY 0.659574 (6310 1160);
PAINT MONO (6310 1160);
DISPLAY INVISIBLE (6310 1160);
FORCEPROP 1 LASTPIN (6300 1150) BN 9
J 2
(6312 1158);
DISPLAY 0.617021 (6312 1158);
PAINT GREEN (6312 1158);
FORCEPROP 1 LAST PATH I311
J 2
(6252 1150);
DISPLAY 0.872340 (6252 1150);
PAINT GREEN (6252 1150);
DISPLAY INVISIBLE (6252 1150);
FORCEPROP 1 LAST HDL_TAP TRUE
J 2
(5925 1025);
DISPLAY 0.872340 (5925 1025);
PAINT ORANGE (5925 1025);
DISPLAY INVISIBLE (5925 1025);
FORCEPROP 1 LAST BODY_TYPE PLUMBING
J 2
(6250 1200);
DISPLAY 0.872340 (6250 1200);
PAINT GREEN (6250 1200);
DISPLAY INVISIBLE (6250 1200);
FORCEPROP 2 LAST CDS_LIB mstr_standard
J 0
(6250 1150);
PAINT ORANGE (6250 1150);
DISPLAY INVISIBLE (6250 1150);
FORCEADD TAP..1
R 2
(6250 950);
FORCEPROP 3 LASTPIN (6300 950) SIG_NAME P3E_CPU0_PE3_OCP_RXN<8>
J 0
(6310 960);
DISPLAY 0.659574 (6310 960);
PAINT MONO (6310 960);
DISPLAY INVISIBLE (6310 960);
FORCEPROP 1 LASTPIN (6300 950) BN 8
J 2
(6312 958);
DISPLAY 0.617021 (6312 958);
PAINT GREEN (6312 958);
FORCEPROP 1 LAST PATH I312
J 2
(6252 950);
DISPLAY 0.872340 (6252 950);
PAINT GREEN (6252 950);
DISPLAY INVISIBLE (6252 950);
FORCEPROP 1 LAST HDL_TAP TRUE
J 2
(5925 825);
DISPLAY 0.872340 (5925 825);
PAINT ORANGE (5925 825);
DISPLAY INVISIBLE (5925 825);
FORCEPROP 1 LAST BODY_TYPE PLUMBING
J 2
(6250 1000);
DISPLAY 0.872340 (6250 1000);
PAINT GREEN (6250 1000);
DISPLAY INVISIBLE (6250 1000);
FORCEPROP 2 LAST CDS_LIB mstr_standard
J 0
(6250 950);
PAINT ORANGE (6250 950);
DISPLAY INVISIBLE (6250 950);
FORCEADD OFFPAGE..2
R 2
(5150 2575);
FORCEPROP 2 LAST $XR0 32 
J 0
(4926 2575);
DISPLAY 0.638298 (4926 2575);
PAINT MONO (4926 2575);
FORCEPROP 2 LAST CDS_LIB mstr_standard
J 2
(5150 2575);
PAINT MONO (5150 2575);
DISPLAY INVISIBLE (5150 2575);
FORCEPROP 1 LAST OFFPAGE TRUE
J 2
(4825 2450);
DISPLAY 0.872340 (4825 2450);
PAINT GREEN (4825 2450);
DISPLAY INVISIBLE (4825 2450);
FORCEPROP 1 LAST COMMENT_BODY TRUE
J 2
(5195 2480);
DISPLAY 0.872340 (5195 2480);
PAINT GREEN (5195 2480);
DISPLAY INVISIBLE (5195 2480);
FORCEPROP 2 LAST PATH I313
J 2
(5400 2625);
DISPLAY 1.021277 (5400 2625);
PAINT ORANGE (5400 2625);
DISPLAY INVISIBLE (5400 2625);
FORCEADD OFFPAGE..2
R 2
(5150 2625);
FORCEPROP 2 LAST $XR0 32 
J 0
(4926 2625);
DISPLAY 0.638298 (4926 2625);
PAINT MONO (4926 2625);
FORCEPROP 2 LAST CDS_LIB mstr_standard
J 2
(5150 2625);
PAINT MONO (5150 2625);
DISPLAY INVISIBLE (5150 2625);
FORCEPROP 1 LAST OFFPAGE TRUE
J 2
(4825 2500);
DISPLAY 0.872340 (4825 2500);
PAINT GREEN (4825 2500);
DISPLAY INVISIBLE (4825 2500);
FORCEPROP 1 LAST COMMENT_BODY TRUE
J 2
(5195 2530);
DISPLAY 0.872340 (5195 2530);
PAINT GREEN (5195 2530);
DISPLAY INVISIBLE (5195 2530);
FORCEPROP 2 LAST PATH I314
J 2
(5400 2675);
DISPLAY 1.021277 (5400 2675);
PAINT ORANGE (5400 2675);
DISPLAY INVISIBLE (5400 2675);
FORCEADD TAP..1
(10250 1850);
FORCEPROP 3 LASTPIN (10200 1850) SIG_NAME P3E_OCP_CPU0_PE3_C_TXN<12>
J 0
(10210 1860);
DISPLAY 0.659574 (10210 1860);
PAINT MONO (10210 1860);
DISPLAY INVISIBLE (10210 1860);
FORCEPROP 1 LASTPIN (10200 1850) BN 12
J 0
(10188 1858);
DISPLAY 0.617021 (10188 1858);
PAINT GREEN (10188 1858);
FORCEPROP 1 LAST PATH I315
J 0
(10248 1850);
DISPLAY 0.872340 (10248 1850);
PAINT GREEN (10248 1850);
DISPLAY INVISIBLE (10248 1850);
FORCEPROP 1 LAST HDL_TAP TRUE
J 0
(10575 1725);
DISPLAY 0.872340 (10575 1725);
PAINT ORANGE (10575 1725);
DISPLAY INVISIBLE (10575 1725);
FORCEPROP 1 LAST BODY_TYPE PLUMBING
J 0
(10250 1900);
DISPLAY 0.872340 (10250 1900);
PAINT GREEN (10250 1900);
DISPLAY INVISIBLE (10250 1900);
FORCEPROP 2 LAST CDS_LIB mstr_standard
J 0
(10250 1850);
PAINT ORANGE (10250 1850);
DISPLAY INVISIBLE (10250 1850);
FORCEADD TAP..1
(10050 2100);
FORCEPROP 3 LASTPIN (10000 2100) SIG_NAME P3E_OCP_CPU0_PE3_C_TXP<13>
J 0
(10010 2110);
DISPLAY 0.659574 (10010 2110);
PAINT MONO (10010 2110);
DISPLAY INVISIBLE (10010 2110);
FORCEPROP 1 LASTPIN (10000 2100) BN 13
J 0
(9988 2108);
DISPLAY 0.617021 (9988 2108);
PAINT GREEN (9988 2108);
FORCEPROP 1 LAST PATH I316
J 0
(10048 2100);
DISPLAY 0.872340 (10048 2100);
PAINT GREEN (10048 2100);
DISPLAY INVISIBLE (10048 2100);
FORCEPROP 1 LAST HDL_TAP TRUE
J 0
(10375 1975);
DISPLAY 0.872340 (10375 1975);
PAINT ORANGE (10375 1975);
DISPLAY INVISIBLE (10375 1975);
FORCEPROP 1 LAST BODY_TYPE PLUMBING
J 0
(10050 2150);
DISPLAY 0.872340 (10050 2150);
PAINT GREEN (10050 2150);
DISPLAY INVISIBLE (10050 2150);
FORCEPROP 2 LAST CDS_LIB mstr_standard
J 0
(10050 2100);
PAINT ORANGE (10050 2100);
DISPLAY INVISIBLE (10050 2100);
FORCEADD TAP..1
(10050 2300);
FORCEPROP 3 LASTPIN (10000 2300) SIG_NAME P3E_OCP_CPU0_PE3_C_TXP<14>
J 0
(10010 2310);
DISPLAY 0.659574 (10010 2310);
PAINT MONO (10010 2310);
DISPLAY INVISIBLE (10010 2310);
FORCEPROP 1 LASTPIN (10000 2300) BN 14
J 0
(9988 2308);
DISPLAY 0.617021 (9988 2308);
PAINT GREEN (9988 2308);
FORCEPROP 1 LAST PATH I317
J 0
(10048 2300);
DISPLAY 0.872340 (10048 2300);
PAINT GREEN (10048 2300);
DISPLAY INVISIBLE (10048 2300);
FORCEPROP 1 LAST HDL_TAP TRUE
J 0
(10375 2175);
DISPLAY 0.872340 (10375 2175);
PAINT ORANGE (10375 2175);
DISPLAY INVISIBLE (10375 2175);
FORCEPROP 1 LAST BODY_TYPE PLUMBING
J 0
(10050 2350);
DISPLAY 0.872340 (10050 2350);
PAINT GREEN (10050 2350);
DISPLAY INVISIBLE (10050 2350);
FORCEPROP 2 LAST CDS_LIB mstr_standard
J 0
(10050 2300);
PAINT ORANGE (10050 2300);
DISPLAY INVISIBLE (10050 2300);
FORCEADD TAP..1
(10050 2500);
FORCEPROP 3 LASTPIN (10000 2500) SIG_NAME P3E_OCP_CPU0_PE3_C_TXP<15>
J 0
(10010 2510);
DISPLAY 0.659574 (10010 2510);
PAINT MONO (10010 2510);
DISPLAY INVISIBLE (10010 2510);
FORCEPROP 1 LASTPIN (10000 2500) BN 15
J 0
(9988 2508);
DISPLAY 0.617021 (9988 2508);
PAINT GREEN (9988 2508);
FORCEPROP 1 LAST PATH I318
J 0
(10048 2500);
DISPLAY 0.872340 (10048 2500);
PAINT GREEN (10048 2500);
DISPLAY INVISIBLE (10048 2500);
FORCEPROP 1 LAST HDL_TAP TRUE
J 0
(10375 2375);
DISPLAY 0.872340 (10375 2375);
PAINT ORANGE (10375 2375);
DISPLAY INVISIBLE (10375 2375);
FORCEPROP 1 LAST BODY_TYPE PLUMBING
J 0
(10050 2550);
DISPLAY 0.872340 (10050 2550);
PAINT GREEN (10050 2550);
DISPLAY INVISIBLE (10050 2550);
FORCEPROP 2 LAST CDS_LIB mstr_standard
J 0
(10050 2500);
PAINT ORANGE (10050 2500);
DISPLAY INVISIBLE (10050 2500);
FORCEADD OFFPAGE..1
R 2
(11025 2500);
FORCEPROP 2 LAST $XR0 106 
J 0
(11211 2500);
DISPLAY 0.638298 (11211 2500);
PAINT MONO (11211 2500);
FORCEPROP 2 LAST CDS_LIB mstr_standard
J 2
(11025 2500);
PAINT ORANGE (11025 2500);
DISPLAY INVISIBLE (11025 2500);
FORCEPROP 1 LAST OFFPAGE TRUE
J 2
(10700 2375);
DISPLAY 0.872340 (10700 2375);
PAINT GREEN (10700 2375);
DISPLAY INVISIBLE (10700 2375);
FORCEPROP 1 LAST COMMENT_BODY TRUE
J 2
(10900 2400);
DISPLAY 0.872340 (10900 2400);
PAINT GREEN (10900 2400);
DISPLAY INVISIBLE (10900 2400);
FORCEPROP 2 LAST PATH I320
J 2
(10850 2575);
DISPLAY 1.021277 (10850 2575);
PAINT ORANGE (10850 2575);
DISPLAY INVISIBLE (10850 2575);
FORCEADD TAP..1
(10250 2450);
FORCEPROP 3 LASTPIN (10200 2450) SIG_NAME P3E_OCP_CPU0_PE3_C_TXN<15>
J 0
(10210 2460);
DISPLAY 0.659574 (10210 2460);
PAINT MONO (10210 2460);
DISPLAY INVISIBLE (10210 2460);
FORCEPROP 1 LASTPIN (10200 2450) BN 15
J 0
(10188 2458);
DISPLAY 0.617021 (10188 2458);
PAINT GREEN (10188 2458);
FORCEPROP 1 LAST PATH I321
J 0
(10248 2450);
DISPLAY 0.872340 (10248 2450);
PAINT GREEN (10248 2450);
DISPLAY INVISIBLE (10248 2450);
FORCEPROP 1 LAST HDL_TAP TRUE
J 0
(10575 2325);
DISPLAY 0.872340 (10575 2325);
PAINT ORANGE (10575 2325);
DISPLAY INVISIBLE (10575 2325);
FORCEPROP 1 LAST BODY_TYPE PLUMBING
J 0
(10250 2500);
DISPLAY 0.872340 (10250 2500);
PAINT GREEN (10250 2500);
DISPLAY INVISIBLE (10250 2500);
FORCEPROP 2 LAST CDS_LIB mstr_standard
J 0
(10250 2450);
PAINT ORANGE (10250 2450);
DISPLAY INVISIBLE (10250 2450);
FORCEADD TAP..1
(10250 2250);
FORCEPROP 3 LASTPIN (10200 2250) SIG_NAME P3E_OCP_CPU0_PE3_C_TXN<14>
J 0
(10210 2260);
DISPLAY 0.659574 (10210 2260);
PAINT MONO (10210 2260);
DISPLAY INVISIBLE (10210 2260);
FORCEPROP 1 LASTPIN (10200 2250) BN 14
J 0
(10188 2258);
DISPLAY 0.617021 (10188 2258);
PAINT GREEN (10188 2258);
FORCEPROP 1 LAST PATH I322
J 0
(10248 2250);
DISPLAY 0.872340 (10248 2250);
PAINT GREEN (10248 2250);
DISPLAY INVISIBLE (10248 2250);
FORCEPROP 1 LAST HDL_TAP TRUE
J 0
(10575 2125);
DISPLAY 0.872340 (10575 2125);
PAINT ORANGE (10575 2125);
DISPLAY INVISIBLE (10575 2125);
FORCEPROP 1 LAST BODY_TYPE PLUMBING
J 0
(10250 2300);
DISPLAY 0.872340 (10250 2300);
PAINT GREEN (10250 2300);
DISPLAY INVISIBLE (10250 2300);
FORCEPROP 2 LAST CDS_LIB mstr_standard
J 0
(10250 2250);
PAINT ORANGE (10250 2250);
DISPLAY INVISIBLE (10250 2250);
FORCEADD TAP..1
(10250 2050);
FORCEPROP 3 LASTPIN (10200 2050) SIG_NAME P3E_OCP_CPU0_PE3_C_TXN<13>
J 0
(10210 2060);
DISPLAY 0.659574 (10210 2060);
PAINT MONO (10210 2060);
DISPLAY INVISIBLE (10210 2060);
FORCEPROP 1 LASTPIN (10200 2050) BN 13
J 0
(10188 2058);
DISPLAY 0.617021 (10188 2058);
PAINT GREEN (10188 2058);
FORCEPROP 1 LAST PATH I323
J 0
(10248 2050);
DISPLAY 0.872340 (10248 2050);
PAINT GREEN (10248 2050);
DISPLAY INVISIBLE (10248 2050);
FORCEPROP 1 LAST HDL_TAP TRUE
J 0
(10575 1925);
DISPLAY 0.872340 (10575 1925);
PAINT ORANGE (10575 1925);
DISPLAY INVISIBLE (10575 1925);
FORCEPROP 1 LAST BODY_TYPE PLUMBING
J 0
(10250 2100);
DISPLAY 0.872340 (10250 2100);
PAINT GREEN (10250 2100);
DISPLAY INVISIBLE (10250 2100);
FORCEPROP 2 LAST CDS_LIB mstr_standard
J 0
(10250 2050);
PAINT ORANGE (10250 2050);
DISPLAY INVISIBLE (10250 2050);
FORCEADD TAP..1
(10250 1650);
FORCEPROP 3 LASTPIN (10200 1650) SIG_NAME P3E_OCP_CPU0_PE3_C_TXN<11>
J 0
(10210 1660);
DISPLAY 0.659574 (10210 1660);
PAINT MONO (10210 1660);
DISPLAY INVISIBLE (10210 1660);
FORCEPROP 1 LASTPIN (10200 1650) BN 11
J 0
(10188 1658);
DISPLAY 0.617021 (10188 1658);
PAINT GREEN (10188 1658);
FORCEPROP 1 LAST PATH I324
J 0
(10248 1650);
DISPLAY 0.872340 (10248 1650);
PAINT GREEN (10248 1650);
DISPLAY INVISIBLE (10248 1650);
FORCEPROP 1 LAST HDL_TAP TRUE
J 0
(10575 1525);
DISPLAY 0.872340 (10575 1525);
PAINT ORANGE (10575 1525);
DISPLAY INVISIBLE (10575 1525);
FORCEPROP 1 LAST BODY_TYPE PLUMBING
J 0
(10250 1700);
DISPLAY 0.872340 (10250 1700);
PAINT GREEN (10250 1700);
DISPLAY INVISIBLE (10250 1700);
FORCEPROP 2 LAST CDS_LIB mstr_standard
J 0
(10250 1650);
PAINT ORANGE (10250 1650);
DISPLAY INVISIBLE (10250 1650);
FORCEADD TAP..1
(10050 1700);
FORCEPROP 3 LASTPIN (10000 1700) SIG_NAME P3E_OCP_CPU0_PE3_C_TXP<11>
J 0
(10010 1710);
DISPLAY 0.659574 (10010 1710);
PAINT MONO (10010 1710);
DISPLAY INVISIBLE (10010 1710);
FORCEPROP 1 LASTPIN (10000 1700) BN 11
J 0
(9988 1708);
DISPLAY 0.617021 (9988 1708);
PAINT GREEN (9988 1708);
FORCEPROP 1 LAST PATH I325
J 0
(10048 1700);
DISPLAY 0.872340 (10048 1700);
PAINT GREEN (10048 1700);
DISPLAY INVISIBLE (10048 1700);
FORCEPROP 1 LAST HDL_TAP TRUE
J 0
(10375 1575);
DISPLAY 0.872340 (10375 1575);
PAINT ORANGE (10375 1575);
DISPLAY INVISIBLE (10375 1575);
FORCEPROP 1 LAST BODY_TYPE PLUMBING
J 0
(10050 1750);
DISPLAY 0.872340 (10050 1750);
PAINT GREEN (10050 1750);
DISPLAY INVISIBLE (10050 1750);
FORCEPROP 2 LAST CDS_LIB mstr_standard
J 0
(10050 1700);
PAINT ORANGE (10050 1700);
DISPLAY INVISIBLE (10050 1700);
FORCEADD TAP..1
(10050 1900);
FORCEPROP 3 LASTPIN (10000 1900) SIG_NAME P3E_OCP_CPU0_PE3_C_TXP<12>
J 0
(10010 1910);
DISPLAY 0.659574 (10010 1910);
PAINT MONO (10010 1910);
DISPLAY INVISIBLE (10010 1910);
FORCEPROP 1 LASTPIN (10000 1900) BN 12
J 0
(9988 1908);
DISPLAY 0.617021 (9988 1908);
PAINT GREEN (9988 1908);
FORCEPROP 1 LAST PATH I326
J 0
(10048 1900);
DISPLAY 0.872340 (10048 1900);
PAINT GREEN (10048 1900);
DISPLAY INVISIBLE (10048 1900);
FORCEPROP 1 LAST HDL_TAP TRUE
J 0
(10375 1775);
DISPLAY 0.872340 (10375 1775);
PAINT ORANGE (10375 1775);
DISPLAY INVISIBLE (10375 1775);
FORCEPROP 1 LAST BODY_TYPE PLUMBING
J 0
(10050 1950);
DISPLAY 0.872340 (10050 1950);
PAINT GREEN (10050 1950);
DISPLAY INVISIBLE (10050 1950);
FORCEPROP 2 LAST CDS_LIB mstr_standard
J 0
(10050 1900);
PAINT ORANGE (10050 1900);
DISPLAY INVISIBLE (10050 1900);
FORCEADD TAP..1
(10250 1450);
FORCEPROP 3 LASTPIN (10200 1450) SIG_NAME P3E_OCP_CPU0_PE3_C_TXN<10>
J 0
(10210 1460);
DISPLAY 0.659574 (10210 1460);
PAINT MONO (10210 1460);
DISPLAY INVISIBLE (10210 1460);
FORCEPROP 1 LASTPIN (10200 1450) BN 10
J 0
(10188 1458);
DISPLAY 0.617021 (10188 1458);
PAINT GREEN (10188 1458);
FORCEPROP 1 LAST PATH I327
J 0
(10248 1450);
DISPLAY 0.872340 (10248 1450);
PAINT GREEN (10248 1450);
DISPLAY INVISIBLE (10248 1450);
FORCEPROP 1 LAST HDL_TAP TRUE
J 0
(10575 1325);
DISPLAY 0.872340 (10575 1325);
PAINT ORANGE (10575 1325);
DISPLAY INVISIBLE (10575 1325);
FORCEPROP 1 LAST BODY_TYPE PLUMBING
J 0
(10250 1500);
DISPLAY 0.872340 (10250 1500);
PAINT GREEN (10250 1500);
DISPLAY INVISIBLE (10250 1500);
FORCEPROP 2 LAST CDS_LIB mstr_standard
J 0
(10250 1450);
PAINT ORANGE (10250 1450);
DISPLAY INVISIBLE (10250 1450);
FORCEADD TAP..1
(10250 1250);
FORCEPROP 3 LASTPIN (10200 1250) SIG_NAME P3E_OCP_CPU0_PE3_C_TXN<9>
J 0
(10210 1260);
DISPLAY 0.659574 (10210 1260);
PAINT MONO (10210 1260);
DISPLAY INVISIBLE (10210 1260);
FORCEPROP 1 LASTPIN (10200 1250) BN 9
J 0
(10188 1258);
DISPLAY 0.617021 (10188 1258);
PAINT GREEN (10188 1258);
FORCEPROP 1 LAST PATH I328
J 0
(10248 1250);
DISPLAY 0.872340 (10248 1250);
PAINT GREEN (10248 1250);
DISPLAY INVISIBLE (10248 1250);
FORCEPROP 1 LAST HDL_TAP TRUE
J 0
(10575 1125);
DISPLAY 0.872340 (10575 1125);
PAINT ORANGE (10575 1125);
DISPLAY INVISIBLE (10575 1125);
FORCEPROP 1 LAST BODY_TYPE PLUMBING
J 0
(10250 1300);
DISPLAY 0.872340 (10250 1300);
PAINT GREEN (10250 1300);
DISPLAY INVISIBLE (10250 1300);
FORCEPROP 2 LAST CDS_LIB mstr_standard
J 0
(10250 1250);
PAINT ORANGE (10250 1250);
DISPLAY INVISIBLE (10250 1250);
FORCEADD TAP..1
(10050 1300);
FORCEPROP 3 LASTPIN (10000 1300) SIG_NAME P3E_OCP_CPU0_PE3_C_TXP<9>
J 0
(10010 1310);
DISPLAY 0.659574 (10010 1310);
PAINT MONO (10010 1310);
DISPLAY INVISIBLE (10010 1310);
FORCEPROP 1 LASTPIN (10000 1300) BN 9
J 0
(9988 1308);
DISPLAY 0.617021 (9988 1308);
PAINT GREEN (9988 1308);
FORCEPROP 1 LAST PATH I329
J 0
(10048 1300);
DISPLAY 0.872340 (10048 1300);
PAINT GREEN (10048 1300);
DISPLAY INVISIBLE (10048 1300);
FORCEPROP 1 LAST HDL_TAP TRUE
J 0
(10375 1175);
DISPLAY 0.872340 (10375 1175);
PAINT ORANGE (10375 1175);
DISPLAY INVISIBLE (10375 1175);
FORCEPROP 1 LAST BODY_TYPE PLUMBING
J 0
(10050 1350);
DISPLAY 0.872340 (10050 1350);
PAINT GREEN (10050 1350);
DISPLAY INVISIBLE (10050 1350);
FORCEPROP 2 LAST CDS_LIB mstr_standard
J 0
(10050 1300);
PAINT ORANGE (10050 1300);
DISPLAY INVISIBLE (10050 1300);
FORCEADD TAP..1
(10050 1500);
FORCEPROP 3 LASTPIN (10000 1500) SIG_NAME P3E_OCP_CPU0_PE3_C_TXP<10>
J 0
(10010 1510);
DISPLAY 0.659574 (10010 1510);
PAINT MONO (10010 1510);
DISPLAY INVISIBLE (10010 1510);
FORCEPROP 1 LASTPIN (10000 1500) BN 10
J 0
(9988 1508);
DISPLAY 0.617021 (9988 1508);
PAINT GREEN (9988 1508);
FORCEPROP 1 LAST PATH I330
J 0
(10048 1500);
DISPLAY 0.872340 (10048 1500);
PAINT GREEN (10048 1500);
DISPLAY INVISIBLE (10048 1500);
FORCEPROP 1 LAST HDL_TAP TRUE
J 0
(10375 1375);
DISPLAY 0.872340 (10375 1375);
PAINT ORANGE (10375 1375);
DISPLAY INVISIBLE (10375 1375);
FORCEPROP 1 LAST BODY_TYPE PLUMBING
J 0
(10050 1550);
DISPLAY 0.872340 (10050 1550);
PAINT GREEN (10050 1550);
DISPLAY INVISIBLE (10050 1550);
FORCEPROP 2 LAST CDS_LIB mstr_standard
J 0
(10050 1500);
PAINT ORANGE (10050 1500);
DISPLAY INVISIBLE (10050 1500);
FORCEADD TAP..1
(10250 1050);
FORCEPROP 3 LASTPIN (10200 1050) SIG_NAME P3E_OCP_CPU0_PE3_C_TXN<8>
J 0
(10210 1060);
DISPLAY 0.659574 (10210 1060);
PAINT MONO (10210 1060);
DISPLAY INVISIBLE (10210 1060);
FORCEPROP 1 LASTPIN (10200 1050) BN 8
J 0
(10188 1058);
DISPLAY 0.617021 (10188 1058);
PAINT GREEN (10188 1058);
FORCEPROP 1 LAST PATH I331
J 0
(10248 1050);
DISPLAY 0.872340 (10248 1050);
PAINT GREEN (10248 1050);
DISPLAY INVISIBLE (10248 1050);
FORCEPROP 1 LAST HDL_TAP TRUE
J 0
(10575 925);
DISPLAY 0.872340 (10575 925);
PAINT ORANGE (10575 925);
DISPLAY INVISIBLE (10575 925);
FORCEPROP 1 LAST BODY_TYPE PLUMBING
J 0
(10250 1100);
DISPLAY 0.872340 (10250 1100);
PAINT GREEN (10250 1100);
DISPLAY INVISIBLE (10250 1100);
FORCEPROP 2 LAST CDS_LIB mstr_standard
J 0
(10250 1050);
PAINT ORANGE (10250 1050);
DISPLAY INVISIBLE (10250 1050);
FORCEADD TAP..1
(10050 1100);
FORCEPROP 3 LASTPIN (10000 1100) SIG_NAME P3E_OCP_CPU0_PE3_C_TXP<8>
J 0
(10010 1110);
DISPLAY 0.659574 (10010 1110);
PAINT MONO (10010 1110);
DISPLAY INVISIBLE (10010 1110);
FORCEPROP 1 LASTPIN (10000 1100) BN 8
J 0
(9988 1108);
DISPLAY 0.617021 (9988 1108);
PAINT GREEN (9988 1108);
FORCEPROP 1 LAST PATH I332
J 0
(10048 1100);
DISPLAY 0.872340 (10048 1100);
PAINT GREEN (10048 1100);
DISPLAY INVISIBLE (10048 1100);
FORCEPROP 1 LAST HDL_TAP TRUE
J 0
(10375 975);
DISPLAY 0.872340 (10375 975);
PAINT ORANGE (10375 975);
DISPLAY INVISIBLE (10375 975);
FORCEPROP 1 LAST BODY_TYPE PLUMBING
J 0
(10050 1150);
DISPLAY 0.872340 (10050 1150);
PAINT GREEN (10050 1150);
DISPLAY INVISIBLE (10050 1150);
FORCEPROP 2 LAST CDS_LIB mstr_standard
J 0
(10050 1100);
PAINT ORANGE (10050 1100);
DISPLAY INVISIBLE (10050 1100);
FORCEADD OFFPAGE..1
R 2
(11025 2575);
FORCEPROP 2 LAST $XR0 106 
J 0
(11211 2575);
DISPLAY 0.638298 (11211 2575);
PAINT MONO (11211 2575);
FORCEPROP 2 LAST CDS_LIB mstr_standard
J 0
(11025 2575);
PAINT ORANGE (11025 2575);
DISPLAY INVISIBLE (11025 2575);
FORCEPROP 1 LAST OFFPAGE TRUE
J 2
(10700 2450);
DISPLAY 0.872340 (10700 2450);
PAINT GREEN (10700 2450);
DISPLAY INVISIBLE (10700 2450);
FORCEPROP 1 LAST COMMENT_BODY TRUE
J 2
(10900 2475);
DISPLAY 0.872340 (10900 2475);
PAINT GREEN (10900 2475);
DISPLAY INVISIBLE (10900 2475);
FORCEPROP 2 LAST PATH I333
J 0
(11200 2650);
DISPLAY 1.021277 (11200 2650);
PAINT ORANGE (11200 2650);
DISPLAY INVISIBLE (11200 2650);
FORCEADD CAP_A..1
(10450 4700);
FORCEPROP 1 LAST VALUE 1.0UF
J 0
(10500 4750);
DISPLAY 0.617021 (10500 4750);
PAINT SKYBLUE (10500 4750);
FORCEPROP 1 LAST TOLERANCE 10%
J 0
(10500 4650);
DISPLAY 0.617021 (10500 4650);
PAINT SKYBLUE (10500 4650);
FORCEPROP 1 LAST VOLTAGE 6.3V
J 0
(10500 4700);
DISPLAY 0.617021 (10500 4700);
PAINT SKYBLUE (10500 4700);
FORCEPROP 1 LAST MATERIAL X6S
J 0
(10500 4600);
DISPLAY 0.617021 (10500 4600);
PAINT SKYBLUE (10500 4600);
FORCEPROP 1 LASTPIN (10450 4600) $PN 2
J 0
(10460 4580);
DISPLAY 0.617021 (10460 4580);
PAINT ORANGE (10460 4580);
FORCEPROP 1 LASTPIN (10450 4800) $PN 1
J 0
(10460 4780);
DISPLAY 0.617021 (10460 4780);
PAINT ORANGE (10460 4780);
FORCEPROP 1 LAST LOCATION C1M21
J 0
(10500 4800);
DISPLAY 0.617021 (10500 4800);
PAINT AQUA (10500 4800);
FORCEPROP 1 LAST PART_NUMBER D97712-004
J 0
(10500 4550);
DISPLAY 0.617021 (10500 4550);
PAINT BLUE (10500 4550);
FORCEPROP 1 LAST PACK_TYPE 0402V
J 0
(10500 4500);
DISPLAY 0.617021 (10500 4500);
PAINT SKYBLUE (10500 4500);
FORCEPROP 0 LAST ROOM IO_SLOT
J 0
(10500 4900);
DISPLAY 1.021277 (10500 4900);
PAINT ORANGE (10500 4900);
DISPLAY INVISIBLE (10500 4900);
FORCEPROP 1 LAST PATH I334
J 0
(10500 4850);
DISPLAY 0.978723 (10500 4850);
PAINT WHITE (10500 4850);
DISPLAY INVISIBLE (10500 4850);
FORCEPROP 2 LAST SEC 1
J 0
(10500 4900);
DISPLAY 0.680851 (10500 4900);
PAINT MONO (10500 4900);
DISPLAY INVISIBLE (10500 4900);
FORCEPROP 2 LAST SEC_TYPE 0402V
J 0
(10500 4900);
DISPLAY 1.021277 (10500 4900);
PAINT ORANGE (10500 4900);
DISPLAY INVISIBLE (10500 4900);
FORCEPROP 2 LAST CDS_SEC 1
J 0
(10500 4850);
PAINT ORANGE (10500 4850);
DISPLAY INVISIBLE (10500 4850);
FORCEPROP 2 LAST CDS_LIB dev_discrete
J 0
(10450 4700);
PAINT ORANGE (10450 4700);
DISPLAY INVISIBLE (10450 4700);
FORCEPROP 2 LAST CDS_LOCATION C1M21
J 0
(10500 4800);
DISPLAY 0.617021 (10500 4800);
PAINT AQUA (10500 4800);
DISPLAY INVISIBLE (10500 4800);
FORCEADD CAP_A..1
(11250 4700);
FORCEPROP 1 LAST LOCATION C1M25
J 0
(11300 4800);
DISPLAY 0.617021 (11300 4800);
PAINT AQUA (11300 4800);
FORCEPROP 1 LAST VALUE 1.0UF
J 0
(11300 4750);
DISPLAY 0.617021 (11300 4750);
PAINT SKYBLUE (11300 4750);
FORCEPROP 1 LAST TOLERANCE 10%
J 0
(11300 4650);
DISPLAY 0.617021 (11300 4650);
PAINT SKYBLUE (11300 4650);
FORCEPROP 1 LAST VOLTAGE 6.3V
J 0
(11300 4700);
DISPLAY 0.617021 (11300 4700);
PAINT SKYBLUE (11300 4700);
FORCEPROP 1 LAST MATERIAL X6S
J 0
(11300 4600);
DISPLAY 0.617021 (11300 4600);
PAINT SKYBLUE (11300 4600);
FORCEPROP 1 LASTPIN (11250 4800) $PN 1
J 0
(11260 4780);
DISPLAY 0.617021 (11260 4780);
PAINT ORANGE (11260 4780);
FORCEPROP 1 LASTPIN (11250 4600) $PN 2
J 0
(11260 4580);
DISPLAY 0.617021 (11260 4580);
PAINT ORANGE (11260 4580);
FORCEPROP 1 LAST PART_NUMBER D97712-004
J 0
(11300 4550);
DISPLAY 0.617021 (11300 4550);
PAINT BLUE (11300 4550);
FORCEPROP 1 LAST PACK_TYPE 0402V
J 0
(11300 4500);
DISPLAY 0.617021 (11300 4500);
PAINT SKYBLUE (11300 4500);
FORCEPROP 0 LAST ROOM IO_SLOT
J 0
(11300 4900);
DISPLAY 1.021277 (11300 4900);
PAINT ORANGE (11300 4900);
DISPLAY INVISIBLE (11300 4900);
FORCEPROP 1 LAST PATH I335
J 0
(11300 4850);
DISPLAY 0.978723 (11300 4850);
PAINT WHITE (11300 4850);
DISPLAY INVISIBLE (11300 4850);
FORCEPROP 2 LAST SEC_TYPE 0402V
J 0
(11300 4900);
DISPLAY 1.021277 (11300 4900);
PAINT ORANGE (11300 4900);
DISPLAY INVISIBLE (11300 4900);
FORCEPROP 2 LAST SEC 1
J 0
(11300 4900);
DISPLAY 0.680851 (11300 4900);
PAINT MONO (11300 4900);
DISPLAY INVISIBLE (11300 4900);
FORCEPROP 2 LAST CDS_LOCATION C1M25
J 0
(11300 4800);
DISPLAY 0.617021 (11300 4800);
PAINT AQUA (11300 4800);
DISPLAY INVISIBLE (11300 4800);
FORCEPROP 2 LAST CDS_LIB dev_discrete
J 0
(11250 4700);
PAINT ORANGE (11250 4700);
DISPLAY INVISIBLE (11250 4700);
FORCEPROP 2 LAST CDS_SEC 1
J 0
(11300 4850);
PAINT ORANGE (11300 4850);
DISPLAY INVISIBLE (11300 4850);
FORCEADD SCONN120_A28699018..1
(8250 2350);
FORCEPROP 2 LASTPIN (8650 1200) $PN 108
J 0
(8660 1210);
DISPLAY 0.617021 (8660 1210);
PAINT ORANGE (8660 1210);
FORCEPROP 2 LASTPIN (8650 1300) $PN 104
J 0
(8660 1310);
DISPLAY 0.617021 (8660 1310);
PAINT ORANGE (8660 1310);
FORCEPROP 2 LASTPIN (8650 1350) $PN 102
J 0
(8660 1360);
DISPLAY 0.617021 (8660 1360);
PAINT ORANGE (8660 1360);
FORCEPROP 2 LASTPIN (8650 1600) $PN 92
J 0
(8660 1610);
DISPLAY 0.617021 (8660 1610);
PAINT ORANGE (8660 1610);
FORCEPROP 2 LASTPIN (8650 1700) $PN 88
J 0
(8660 1710);
DISPLAY 0.617021 (8660 1710);
PAINT ORANGE (8660 1710);
FORCEPROP 2 LASTPIN (8650 1800) $PN 84
J 0
(8660 1810);
DISPLAY 0.617021 (8660 1810);
PAINT ORANGE (8660 1810);
FORCEPROP 2 LASTPIN (8650 1900) $PN 80
J 0
(8660 1910);
DISPLAY 0.617021 (8660 1910);
PAINT ORANGE (8660 1910);
FORCEPROP 2 LASTPIN (7850 1350) $PN 101
J 2
(7840 1360);
DISPLAY 0.617021 (7840 1360);
PAINT ORANGE (7840 1360);
FORCEPROP 2 LASTPIN (7850 900) $PN 119
J 2
(7840 910);
DISPLAY 0.617021 (7840 910);
PAINT ORANGE (7840 910);
FORCEPROP 2 LASTPIN (7850 1000) $PN 115
J 2
(7840 1010);
DISPLAY 0.617021 (7840 1010);
PAINT ORANGE (7840 1010);
FORCEPROP 2 LASTPIN (8650 1050) $PN 114
J 0
(8660 1060);
DISPLAY 0.617021 (8660 1060);
PAINT ORANGE (8660 1060);
FORCEPROP 2 LASTPIN (7850 1050) $PN 113
J 2
(7840 1060);
DISPLAY 0.617021 (7840 1060);
PAINT ORANGE (7840 1060);
FORCEPROP 2 LASTPIN (8650 1100) $PN 112
J 0
(8660 1110);
DISPLAY 0.617021 (8660 1110);
PAINT ORANGE (8660 1110);
FORCEPROP 2 LASTPIN (7850 1100) $PN 111
J 2
(7840 1110);
DISPLAY 0.617021 (7840 1110);
PAINT ORANGE (7840 1110);
FORCEPROP 2 LASTPIN (8650 1150) $PN 110
J 0
(8660 1160);
DISPLAY 0.617021 (8660 1160);
PAINT ORANGE (8660 1160);
FORCEPROP 2 LASTPIN (7850 1150) $PN 109
J 2
(7840 1160);
DISPLAY 0.617021 (7840 1160);
PAINT ORANGE (7840 1160);
FORCEPROP 2 LASTPIN (7850 1200) $PN 107
J 2
(7840 1210);
DISPLAY 0.617021 (7840 1210);
PAINT ORANGE (7840 1210);
FORCEPROP 2 LASTPIN (7850 1250) $PN 105
J 2
(7840 1260);
DISPLAY 0.617021 (7840 1260);
PAINT ORANGE (7840 1260);
FORCEPROP 2 LASTPIN (7850 1300) $PN 103
J 2
(7840 1310);
DISPLAY 0.617021 (7840 1310);
PAINT ORANGE (7840 1310);
FORCEPROP 2 LASTPIN (8650 1400) $PN 100
J 0
(8660 1410);
DISPLAY 0.617021 (8660 1410);
PAINT ORANGE (8660 1410);
FORCEPROP 2 LASTPIN (7850 1400) $PN 99
J 2
(7840 1410);
DISPLAY 0.617021 (7840 1410);
PAINT ORANGE (7840 1410);
FORCEPROP 2 LASTPIN (7850 1450) $PN 97
J 2
(7840 1460);
DISPLAY 0.617021 (7840 1460);
PAINT ORANGE (7840 1460);
FORCEPROP 2 LASTPIN (7850 1500) $PN 95
J 2
(7840 1510);
DISPLAY 0.617021 (7840 1510);
PAINT ORANGE (7840 1510);
FORCEPROP 2 LASTPIN (7850 1550) $PN 93
J 2
(7840 1560);
DISPLAY 0.617021 (7840 1560);
PAINT ORANGE (7840 1560);
FORCEPROP 2 LASTPIN (7850 1600) $PN 91
J 2
(7840 1610);
DISPLAY 0.617021 (7840 1610);
PAINT ORANGE (7840 1610);
FORCEPROP 2 LASTPIN (8650 1650) $PN 90
J 0
(8660 1660);
DISPLAY 0.617021 (8660 1660);
PAINT ORANGE (8660 1660);
FORCEPROP 2 LASTPIN (7850 1650) $PN 89
J 2
(7840 1660);
DISPLAY 0.617021 (7840 1660);
PAINT ORANGE (7840 1660);
FORCEPROP 2 LASTPIN (7850 1700) $PN 87
J 2
(7840 1710);
DISPLAY 0.617021 (7840 1710);
PAINT ORANGE (7840 1710);
FORCEPROP 2 LASTPIN (8650 1750) $PN 86
J 0
(8660 1760);
DISPLAY 0.617021 (8660 1760);
PAINT ORANGE (8660 1760);
FORCEPROP 2 LASTPIN (7850 1750) $PN 85
J 2
(7840 1760);
DISPLAY 0.617021 (7840 1760);
PAINT ORANGE (7840 1760);
FORCEPROP 2 LASTPIN (7850 1850) $PN 81
J 2
(7840 1860);
DISPLAY 0.617021 (7840 1860);
PAINT ORANGE (7840 1860);
FORCEPROP 2 LASTPIN (7850 1900) $PN 79
J 2
(7840 1910);
DISPLAY 0.617021 (7840 1910);
PAINT ORANGE (7840 1910);
FORCEPROP 2 LASTPIN (8650 1950) $PN 78
J 0
(8660 1960);
DISPLAY 0.617021 (8660 1960);
PAINT ORANGE (8660 1960);
FORCEPROP 2 LASTPIN (7850 1950) $PN 77
J 2
(7840 1960);
DISPLAY 0.617021 (7840 1960);
PAINT ORANGE (7840 1960);
FORCEPROP 2 LASTPIN (7850 2000) $PN 75
J 2
(7840 2010);
DISPLAY 0.617021 (7840 2010);
PAINT ORANGE (7840 2010);
FORCEPROP 2 LASTPIN (8650 2050) $PN 74
J 0
(8660 2060);
DISPLAY 0.617021 (8660 2060);
PAINT ORANGE (8660 2060);
FORCEPROP 2 LASTPIN (7850 2050) $PN 73
J 2
(7840 2060);
DISPLAY 0.617021 (7840 2060);
PAINT ORANGE (7840 2060);
FORCEPROP 2 LASTPIN (8650 2100) $PN 72
J 0
(8660 2110);
DISPLAY 0.617021 (8660 2110);
PAINT ORANGE (8660 2110);
FORCEPROP 2 LASTPIN (7850 2100) $PN 71
J 2
(7840 2110);
DISPLAY 0.617021 (7840 2110);
PAINT ORANGE (7840 2110);
FORCEPROP 2 LASTPIN (8650 2150) $PN 70
J 0
(8660 2160);
DISPLAY 0.617021 (8660 2160);
PAINT ORANGE (8660 2160);
FORCEPROP 2 LASTPIN (7850 2150) $PN 69
J 2
(7840 2160);
DISPLAY 0.617021 (7840 2160);
PAINT ORANGE (7840 2160);
FORCEPROP 2 LASTPIN (8650 2200) $PN 68
J 0
(8660 2210);
DISPLAY 0.617021 (8660 2210);
PAINT ORANGE (8660 2210);
FORCEPROP 2 LASTPIN (7850 2200) $PN 67
J 2
(7840 2210);
DISPLAY 0.617021 (7840 2210);
PAINT ORANGE (7840 2210);
FORCEPROP 2 LASTPIN (8650 2250) $PN 66
J 0
(8660 2260);
DISPLAY 0.617021 (8660 2260);
PAINT ORANGE (8660 2260);
FORCEPROP 2 LASTPIN (7850 2250) $PN 65
J 2
(7840 2260);
DISPLAY 0.617021 (7840 2260);
PAINT ORANGE (7840 2260);
FORCEPROP 2 LASTPIN (8650 2300) $PN 64
J 0
(8660 2310);
DISPLAY 0.617021 (8660 2310);
PAINT ORANGE (8660 2310);
FORCEPROP 2 LASTPIN (7850 2300) $PN 63
J 2
(7840 2310);
DISPLAY 0.617021 (7840 2310);
PAINT ORANGE (7840 2310);
FORCEPROP 2 LASTPIN (8650 2400) $PN 60
J 0
(8660 2410);
DISPLAY 0.617021 (8660 2410);
PAINT ORANGE (8660 2410);
FORCEPROP 2 LASTPIN (7850 2400) $PN 59
J 2
(7840 2410);
DISPLAY 0.617021 (7840 2410);
PAINT ORANGE (7840 2410);
FORCEPROP 2 LASTPIN (8650 2450) $PN 58
J 0
(8660 2460);
DISPLAY 0.617021 (8660 2460);
PAINT ORANGE (8660 2460);
FORCEPROP 2 LASTPIN (7850 2450) $PN 57
J 2
(7840 2460);
DISPLAY 0.617021 (7840 2460);
PAINT ORANGE (7840 2460);
FORCEPROP 2 LASTPIN (8650 2500) $PN 56
J 0
(8660 2510);
DISPLAY 0.617021 (8660 2510);
PAINT ORANGE (8660 2510);
FORCEPROP 2 LASTPIN (7850 2500) $PN 55
J 2
(7840 2510);
DISPLAY 0.617021 (7840 2510);
PAINT ORANGE (7840 2510);
FORCEPROP 2 LASTPIN (8650 2600) $PN 52
J 0
(8660 2610);
DISPLAY 0.617021 (8660 2610);
PAINT ORANGE (8660 2610);
FORCEPROP 2 LASTPIN (7850 2600) $PN 51
J 2
(7840 2610);
DISPLAY 0.617021 (7840 2610);
PAINT ORANGE (7840 2610);
FORCEPROP 2 LASTPIN (8650 2650) $PN 50
J 0
(8660 2660);
DISPLAY 0.617021 (8660 2660);
PAINT ORANGE (8660 2660);
FORCEPROP 2 LASTPIN (7850 2650) $PN 49
J 2
(7840 2660);
DISPLAY 0.617021 (7840 2660);
PAINT ORANGE (7840 2660);
FORCEPROP 2 LASTPIN (8650 2700) $PN 48
J 0
(8660 2710);
DISPLAY 0.617021 (8660 2710);
PAINT ORANGE (8660 2710);
FORCEPROP 2 LASTPIN (7850 2700) $PN 47
J 2
(7840 2710);
DISPLAY 0.617021 (7840 2710);
PAINT ORANGE (7840 2710);
FORCEPROP 2 LASTPIN (8650 2750) $PN 46
J 0
(8660 2760);
DISPLAY 0.617021 (8660 2760);
PAINT ORANGE (8660 2760);
FORCEPROP 2 LASTPIN (7850 2750) $PN 45
J 2
(7840 2760);
DISPLAY 0.617021 (7840 2760);
PAINT ORANGE (7840 2760);
FORCEPROP 2 LASTPIN (8650 2800) $PN 44
J 0
(8660 2810);
DISPLAY 0.617021 (8660 2810);
PAINT ORANGE (8660 2810);
FORCEPROP 2 LASTPIN (7850 2800) $PN 43
J 2
(7840 2810);
DISPLAY 0.617021 (7840 2810);
PAINT ORANGE (7840 2810);
FORCEPROP 2 LASTPIN (8650 2850) $PN 42
J 0
(8660 2860);
DISPLAY 0.617021 (8660 2860);
PAINT ORANGE (8660 2860);
FORCEPROP 2 LASTPIN (7850 2850) $PN 41
J 2
(7840 2860);
DISPLAY 0.617021 (7840 2860);
PAINT ORANGE (7840 2860);
FORCEPROP 2 LASTPIN (8650 2900) $PN 40
J 0
(8660 2910);
DISPLAY 0.617021 (8660 2910);
PAINT ORANGE (8660 2910);
FORCEPROP 2 LASTPIN (7850 2900) $PN 39
J 2
(7840 2910);
DISPLAY 0.617021 (7840 2910);
PAINT ORANGE (7840 2910);
FORCEPROP 2 LASTPIN (8650 2950) $PN 38
J 0
(8660 2960);
DISPLAY 0.617021 (8660 2960);
PAINT ORANGE (8660 2960);
FORCEPROP 2 LASTPIN (8650 3000) $PN 36
J 0
(8660 3010);
DISPLAY 0.617021 (8660 3010);
PAINT ORANGE (8660 3010);
FORCEPROP 2 LASTPIN (7850 3000) $PN 35
J 2
(7840 3010);
DISPLAY 0.617021 (7840 3010);
PAINT ORANGE (7840 3010);
FORCEPROP 2 LASTPIN (8650 3050) $PN 34
J 0
(8660 3060);
DISPLAY 0.617021 (8660 3060);
PAINT ORANGE (8660 3060);
FORCEPROP 2 LASTPIN (8650 3100) $PN 32
J 0
(8660 3110);
DISPLAY 0.617021 (8660 3110);
PAINT ORANGE (8660 3110);
FORCEPROP 2 LASTPIN (7850 3100) $PN 31
J 2
(7840 3110);
DISPLAY 0.617021 (7840 3110);
PAINT ORANGE (7840 3110);
FORCEPROP 2 LASTPIN (8650 3150) $PN 30
J 0
(8660 3160);
DISPLAY 0.617021 (8660 3160);
PAINT ORANGE (8660 3160);
FORCEPROP 2 LASTPIN (7850 3150) $PN 29
J 2
(7840 3160);
DISPLAY 0.617021 (7840 3160);
PAINT ORANGE (7840 3160);
FORCEPROP 2 LASTPIN (8650 3200) $PN 28
J 0
(8660 3210);
DISPLAY 0.617021 (8660 3210);
PAINT ORANGE (8660 3210);
FORCEPROP 2 LASTPIN (8650 3250) $PN 26
J 0
(8660 3260);
DISPLAY 0.617021 (8660 3260);
PAINT ORANGE (8660 3260);
FORCEPROP 2 LASTPIN (8650 3300) $PN 24
J 0
(8660 3310);
DISPLAY 0.617021 (8660 3310);
PAINT ORANGE (8660 3310);
FORCEPROP 2 LASTPIN (8650 3350) $PN 22
J 0
(8660 3360);
DISPLAY 0.617021 (8660 3360);
PAINT ORANGE (8660 3360);
FORCEPROP 2 LASTPIN (7850 3350) $PN 21
J 2
(7840 3360);
DISPLAY 0.617021 (7840 3360);
PAINT ORANGE (7840 3360);
FORCEPROP 2 LASTPIN (8650 3400) $PN 20
J 0
(8660 3410);
DISPLAY 0.617021 (8660 3410);
PAINT ORANGE (8660 3410);
FORCEPROP 2 LASTPIN (7850 3400) $PN 19
J 2
(7840 3410);
DISPLAY 0.617021 (7840 3410);
PAINT ORANGE (7840 3410);
FORCEPROP 2 LASTPIN (8650 3450) $PN 18
J 0
(8660 3460);
DISPLAY 0.617021 (8660 3460);
PAINT ORANGE (8660 3460);
FORCEPROP 2 LASTPIN (7850 3450) $PN 17
J 2
(7840 3460);
DISPLAY 0.617021 (7840 3460);
PAINT ORANGE (7840 3460);
FORCEPROP 2 LASTPIN (8650 3500) $PN 16
J 0
(8660 3510);
DISPLAY 0.617021 (8660 3510);
PAINT ORANGE (8660 3510);
FORCEPROP 2 LASTPIN (8650 3550) $PN 14
J 0
(8660 3560);
DISPLAY 0.617021 (8660 3560);
PAINT ORANGE (8660 3560);
FORCEPROP 2 LASTPIN (7850 3550) $PN 13
J 2
(7840 3560);
DISPLAY 0.617021 (7840 3560);
PAINT ORANGE (7840 3560);
FORCEPROP 2 LASTPIN (8650 3600) $PN 12
J 0
(8660 3610);
DISPLAY 0.617021 (8660 3610);
PAINT ORANGE (8660 3610);
FORCEPROP 2 LASTPIN (7850 3600) $PN 11
J 2
(7840 3610);
DISPLAY 0.617021 (7840 3610);
PAINT ORANGE (7840 3610);
FORCEPROP 2 LASTPIN (8650 3650) $PN 10
J 0
(8660 3660);
DISPLAY 0.617021 (8660 3660);
PAINT ORANGE (8660 3660);
FORCEPROP 2 LASTPIN (7850 3650) $PN 9
J 2
(7840 3660);
DISPLAY 0.617021 (7840 3660);
PAINT ORANGE (7840 3660);
FORCEPROP 2 LASTPIN (7850 3700) $PN 7
J 2
(7840 3710);
DISPLAY 0.617021 (7840 3710);
PAINT ORANGE (7840 3710);
FORCEPROP 2 LASTPIN (8650 3750) $PN 6
J 0
(8660 3760);
DISPLAY 0.617021 (8660 3760);
PAINT ORANGE (8660 3760);
FORCEPROP 2 LASTPIN (7850 3750) $PN 5
J 2
(7840 3760);
DISPLAY 0.617021 (7840 3760);
PAINT ORANGE (7840 3760);
FORCEPROP 2 LASTPIN (8650 3800) $PN 4
J 0
(8660 3810);
DISPLAY 0.617021 (8660 3810);
PAINT ORANGE (8660 3810);
FORCEPROP 2 LASTPIN (8650 3850) $PN 2
J 0
(8660 3860);
DISPLAY 0.617021 (8660 3860);
PAINT ORANGE (8660 3860);
FORCEPROP 2 LASTPIN (7850 3800) $PN 3
J 2
(7840 3810);
DISPLAY 0.617021 (7840 3810);
PAINT ORANGE (7840 3810);
FORCEPROP 2 LASTPIN (7850 3850) $PN 1
J 2
(7840 3860);
DISPLAY 0.617021 (7840 3860);
PAINT ORANGE (7840 3860);
FORCEPROP 1 LAST MATERIAL SCONN
J 0
(7900 4050);
DISPLAY 0.617021 (7900 4050);
PAINT SKYBLUE (7900 4050);
FORCEPROP 1 LAST PART_NUMBER A28699-018
J 0
(7900 750);
DISPLAY 0.617021 (7900 750);
PAINT BLUE (7900 750);
FORCEPROP 2 LASTPIN (8650 2350) $PN 62
J 0
(8660 2360);
DISPLAY 0.617021 (8660 2360);
PAINT ORANGE (8660 2360);
FORCEPROP 2 LASTPIN (7850 2350) $PN 61
J 2
(7840 2360);
DISPLAY 0.617021 (7840 2360);
PAINT ORANGE (7840 2360);
FORCEPROP 2 LASTPIN (8650 900) $PN 120
J 0
(8660 910);
DISPLAY 0.617021 (8660 910);
PAINT ORANGE (8660 910);
FORCEPROP 2 LASTPIN (8650 1850) $PN 82
J 0
(8660 1860);
DISPLAY 0.617021 (8660 1860);
PAINT ORANGE (8660 1860);
FORCEPROP 2 LASTPIN (7850 2550) $PN 53
J 2
(7840 2560);
DISPLAY 0.617021 (7840 2560);
PAINT ORANGE (7840 2560);
FORCEPROP 2 LASTPIN (8650 2550) $PN 54
J 0
(8660 2560);
DISPLAY 0.617021 (8660 2560);
PAINT ORANGE (8660 2560);
FORCEPROP 2 LASTPIN (7850 3500) $PN 15
J 2
(7840 3510);
DISPLAY 0.617021 (7840 3510);
PAINT ORANGE (7840 3510);
FORCEPROP 2 LASTPIN (7850 3250) $PN 25
J 2
(7840 3260);
DISPLAY 0.617021 (7840 3260);
PAINT ORANGE (7840 3260);
FORCEPROP 2 LASTPIN (7850 3300) $PN 23
J 2
(7840 3310);
DISPLAY 0.617021 (7840 3310);
PAINT ORANGE (7840 3310);
FORCEPROP 2 LASTPIN (7850 3200) $PN 27
J 2
(7840 3210);
DISPLAY 0.617021 (7840 3210);
PAINT ORANGE (7840 3210);
FORCEPROP 2 LASTPIN (8650 3700) $PN 8
J 0
(8660 3710);
DISPLAY 0.617021 (8660 3710);
PAINT ORANGE (8660 3710);
FORCEPROP 2 LASTPIN (7850 1800) $PN 83
J 2
(7840 1810);
DISPLAY 0.617021 (7840 1810);
PAINT ORANGE (7840 1810);
FORCEPROP 2 LASTPIN (8650 2000) $PN 76
J 0
(8660 2010);
DISPLAY 0.617021 (8660 2010);
PAINT ORANGE (8660 2010);
FORCEPROP 2 LASTPIN (7850 3050) $PN 33
J 2
(7840 3060);
DISPLAY 0.617021 (7840 3060);
PAINT ORANGE (7840 3060);
FORCEPROP 2 LASTPIN (7850 2950) $PN 37
J 2
(7840 2960);
DISPLAY 0.617021 (7840 2960);
PAINT ORANGE (7840 2960);
FORCEPROP 1 LAST LOCATION J9B3
J 0
(8150 4100);
DISPLAY 0.617021 (8150 4100);
PAINT AQUA (8150 4100);
FORCEPROP 2 LASTPIN (7850 950) $PN 117
J 2
(7840 960);
DISPLAY 0.617021 (7840 960);
PAINT ORANGE (7840 960);
FORCEPROP 2 LASTPIN (8650 950) $PN 118
J 0
(8660 960);
DISPLAY 0.617021 (8660 960);
PAINT ORANGE (8660 960);
FORCEPROP 2 LASTPIN (8650 1000) $PN 116
J 0
(8660 1010);
DISPLAY 0.617021 (8660 1010);
PAINT ORANGE (8660 1010);
FORCEPROP 2 LASTPIN (8650 1550) $PN 94
J 0
(8660 1560);
DISPLAY 0.617021 (8660 1560);
PAINT ORANGE (8660 1560);
FORCEPROP 2 LASTPIN (8650 1500) $PN 96
J 0
(8660 1510);
DISPLAY 0.617021 (8660 1510);
PAINT ORANGE (8660 1510);
FORCEPROP 2 LASTPIN (8650 1450) $PN 98
J 0
(8660 1460);
DISPLAY 0.617021 (8660 1460);
PAINT ORANGE (8660 1460);
FORCEPROP 2 LASTPIN (8650 1250) $PN 106
J 0
(8660 1260);
DISPLAY 0.617021 (8660 1260);
PAINT ORANGE (8660 1260);
FORCEPROP 0 LAST GROUP NO_KR
J 0
(7903 708);
DISPLAY 0.638298 (7903 708);
PAINT BROWN (7903 708);
DISPLAY BOTH (7903 708);
FORCEPROP 2 LAST CDS_LIB mstr_sconn
J 0
(8250 2350);
PAINT ORANGE (8250 2350);
DISPLAY INVISIBLE (8250 2350);
FORCEPROP 2 LAST SEC_TYPE SM
J 0
(8150 4150);
DISPLAY 1.021277 (8150 4150);
PAINT ORANGE (8150 4150);
DISPLAY INVISIBLE (8150 4150);
FORCEPROP 2 LAST SEC 1
J 0
(8150 4150);
DISPLAY 0.680851 (8150 4150);
PAINT MONO (8150 4150);
DISPLAY INVISIBLE (8150 4150);
FORCEPROP 2 LAST CDS_LOCATION J9B3
J 0
(8150 4100);
DISPLAY 0.617021 (8150 4100);
PAINT AQUA (8150 4100);
DISPLAY INVISIBLE (8150 4100);
FORCEPROP 1 LAST PATH I336
J 0
(8200 4050);
PAINT GREEN (8200 4050);
DISPLAY INVISIBLE (8200 4050);
FORCEPROP 0 LAST ROOM IO_SLOT
J 0
(8150 4200);
DISPLAY 1.021277 (8150 4200);
PAINT ORANGE (8150 4200);
DISPLAY INVISIBLE (8150 4200);
FORCEPROP 1 LAST PACK_TYPE SM
J 0
(7900 4150);
PAINT SKYBLUE (7900 4150);
DISPLAY INVISIBLE (7900 4150);
FORCEADD RES..1
(6700 2750);
FORCEPROP 1 LASTPIN (6600 2750) $PN 1
J 0
(6612 2762);
DISPLAY 0.617021 (6612 2762);
PAINT ORANGE (6612 2762);
FORCEPROP 1 LAST PART_NUMBER G21497-005
J 0
(6850 2700);
DISPLAY 0.617021 (6850 2700);
PAINT BLUE (6850 2700);
FORCEPROP 1 LAST TOLERANCE 5%
J 0
(6750 2700);
DISPLAY 0.617021 (6750 2700);
PAINT SKYBLUE (6750 2700);
FORCEPROP 1 LASTPIN (6800 2750) $PN 2
J 0
(6762 2762);
DISPLAY 0.617021 (6762 2762);
PAINT ORANGE (6762 2762);
FORCEPROP 1 LAST LOCATION R1M16
J 0
(6625 2825);
DISPLAY 0.617021 (6625 2825);
PAINT AQUA (6625 2825);
FORCEPROP 1 LAST VALUE 0.0
J 2
(6650 2700);
DISPLAY 0.617021 (6650 2700);
PAINT SKYBLUE (6650 2700);
FORCEPROP 1 LAST WATTAGE 1/16W
J 0
(6550 2650);
DISPLAY 0.617021 (6550 2650);
PAINT SKYBLUE (6550 2650);
FORCEPROP 1 LAST MATERIAL CHIP
J 0
(6700 2650);
DISPLAY 0.617021 (6700 2650);
PAINT SKYBLUE (6700 2650);
FORCEPROP 1 LAST PACK_TYPE 0402
J 0
(6875 2650);
DISPLAY 0.617021 (6875 2650);
PAINT SKYBLUE (6875 2650);
FORCEPROP 0 LAST ROOM IO_SLOT
J 0
(6750 2850);
DISPLAY 1.021277 (6750 2850);
PAINT ORANGE (6750 2850);
DISPLAY INVISIBLE (6750 2850);
FORCEPROP 1 LAST PATH I337
J 0
(6650 2900);
DISPLAY 0.978723 (6650 2900);
PAINT WHITE (6650 2900);
DISPLAY INVISIBLE (6650 2900);
FORCEPROP 2 LAST CDS_LOCATION R1M16
J 0
(6825 2700);
DISPLAY 0.617021 (6825 2700);
PAINT AQUA (6825 2700);
DISPLAY INVISIBLE (6825 2700);
FORCEPROP 2 LAST SEC 1
J 0
(6650 2950);
DISPLAY 0.680851 (6650 2950);
PAINT MONO (6650 2950);
DISPLAY INVISIBLE (6650 2950);
FORCEPROP 2 LAST SEC_TYPE 0402
J 0
(6650 2950);
DISPLAY 1.021277 (6650 2950);
PAINT ORANGE (6650 2950);
DISPLAY INVISIBLE (6650 2950);
FORCEPROP 2 LAST CDS_LIB mstr_discrete
J 0
(6700 2750);
PAINT ORANGE (6700 2750);
DISPLAY INVISIBLE (6700 2750);
FORCEADD RES..1
(6375 2800);
FORCEPROP 1 LAST TOLERANCE 5%
J 0
(6425 2750);
DISPLAY 0.617021 (6425 2750);
PAINT SKYBLUE (6425 2750);
FORCEPROP 1 LASTPIN (6275 2800) $PN 1
J 0
(6287 2812);
DISPLAY 0.617021 (6287 2812);
PAINT ORANGE (6287 2812);
FORCEPROP 1 LAST PART_NUMBER G21497-005
J 0
(6050 2800);
DISPLAY 0.617021 (6050 2800);
PAINT BLUE (6050 2800);
FORCEPROP 1 LAST VALUE 0.0
J 2
(6325 2750);
DISPLAY 0.617021 (6325 2750);
PAINT SKYBLUE (6325 2750);
FORCEPROP 1 LASTPIN (6475 2800) $PN 2
J 0
(6437 2812);
DISPLAY 0.617021 (6437 2812);
PAINT ORANGE (6437 2812);
FORCEPROP 1 LAST LOCATION R1M17
J 0
(6325 2850);
DISPLAY 0.617021 (6325 2850);
PAINT AQUA (6325 2850);
FORCEPROP 1 LAST WATTAGE 1/16W
J 0
(5900 2750);
DISPLAY 0.617021 (5900 2750);
PAINT SKYBLUE (5900 2750);
FORCEPROP 1 LAST MATERIAL CHIP
J 0
(5775 2750);
DISPLAY 0.617021 (5775 2750);
PAINT SKYBLUE (5775 2750);
FORCEPROP 1 LAST PACK_TYPE 0402
J 0
(6100 2750);
DISPLAY 0.617021 (6100 2750);
PAINT SKYBLUE (6100 2750);
FORCEPROP 0 LAST ROOM IO_SLOT
J 0
(6425 2900);
DISPLAY 1.021277 (6425 2900);
PAINT ORANGE (6425 2900);
DISPLAY INVISIBLE (6425 2900);
FORCEPROP 1 LAST PATH I338
J 0
(6325 2950);
DISPLAY 0.978723 (6325 2950);
PAINT WHITE (6325 2950);
DISPLAY INVISIBLE (6325 2950);
FORCEPROP 2 LAST CDS_LOCATION R1M17
J 0
(6475 2800);
DISPLAY 0.617021 (6475 2800);
PAINT AQUA (6475 2800);
DISPLAY INVISIBLE (6475 2800);
FORCEPROP 2 LAST SEC 1
J 0
(6325 3000);
DISPLAY 0.680851 (6325 3000);
PAINT MONO (6325 3000);
DISPLAY INVISIBLE (6325 3000);
FORCEPROP 2 LAST CDS_LIB mstr_discrete
J 0
(6375 2800);
PAINT ORANGE (6375 2800);
DISPLAY INVISIBLE (6375 2800);
FORCEPROP 2 LAST SEC_TYPE 0402
J 0
(6325 3000);
DISPLAY 1.021277 (6325 3000);
PAINT ORANGE (6325 3000);
DISPLAY INVISIBLE (6325 3000);
FORCEADD RES..1
(6375 3200);
FORCEPROP 1 LAST PART_NUMBER G21497-005
J 0
(6050 3200);
DISPLAY 0.617021 (6050 3200);
PAINT BLUE (6050 3200);
FORCEPROP 1 LAST VALUE 0.0
J 2
(6325 3150);
DISPLAY 0.617021 (6325 3150);
PAINT SKYBLUE (6325 3150);
FORCEPROP 1 LAST TOLERANCE 5%
J 0
(6425 3150);
DISPLAY 0.617021 (6425 3150);
PAINT SKYBLUE (6425 3150);
FORCEPROP 1 LASTPIN (6275 3200) $PN 1
J 0
(6287 3212);
DISPLAY 0.617021 (6287 3212);
PAINT ORANGE (6287 3212);
FORCEPROP 1 LAST WATTAGE 1/16W
J 0
(6475 3275);
DISPLAY 0.617021 (6475 3275);
PAINT SKYBLUE (6475 3275);
FORCEPROP 1 LAST MATERIAL CHIP
J 0
(6650 3275);
DISPLAY 0.617021 (6650 3275);
PAINT SKYBLUE (6650 3275);
FORCEPROP 1 LAST PACK_TYPE 0402
J 0
(6525 3200);
DISPLAY 0.617021 (6525 3200);
PAINT SKYBLUE (6525 3200);
FORCEPROP 1 LASTPIN (6475 3200) $PN 2
J 0
(6437 3212);
DISPLAY 0.617021 (6437 3212);
PAINT ORANGE (6437 3212);
FORCEPROP 1 LAST LOCATION R1M15
J 0
(6300 3275);
DISPLAY 0.617021 (6300 3275);
PAINT AQUA (6300 3275);
FORCEPROP 0 LAST ROOM IO_SLOT
J 0
(6425 3300);
DISPLAY 1.021277 (6425 3300);
PAINT ORANGE (6425 3300);
DISPLAY INVISIBLE (6425 3300);
FORCEPROP 1 LAST PATH I339
J 0
(6325 3350);
DISPLAY 0.978723 (6325 3350);
PAINT WHITE (6325 3350);
DISPLAY INVISIBLE (6325 3350);
FORCEPROP 2 LAST CDS_LOCATION R1M15
J 0
(6500 3200);
DISPLAY 0.617021 (6500 3200);
PAINT AQUA (6500 3200);
DISPLAY INVISIBLE (6500 3200);
FORCEPROP 2 LAST SEC 1
J 0
(6325 3400);
DISPLAY 0.680851 (6325 3400);
PAINT MONO (6325 3400);
DISPLAY INVISIBLE (6325 3400);
FORCEPROP 2 LAST CDS_LIB mstr_discrete
J 0
(6375 3200);
PAINT ORANGE (6375 3200);
DISPLAY INVISIBLE (6375 3200);
FORCEPROP 2 LAST SEC_TYPE 0402
J 0
(6325 3400);
DISPLAY 1.021277 (6325 3400);
PAINT ORANGE (6325 3400);
DISPLAY INVISIBLE (6325 3400);
FORCEADD RES..1
(10250 3000);
FORCEPROP 1 LAST LOCATION R1M18
J 0
(10175 3050);
DISPLAY 0.617021 (10175 3050);
PAINT AQUA (10175 3050);
FORCEPROP 1 LASTPIN (10150 3000) $PN 1
J 0
(10162 3012);
DISPLAY 0.617021 (10162 3012);
PAINT ORANGE (10162 3012);
FORCEPROP 1 LASTPIN (10350 3000) $PN 2
J 0
(10312 3012);
DISPLAY 0.617021 (10312 3012);
PAINT ORANGE (10312 3012);
FORCEPROP 1 LAST PART_NUMBER G21497-005
J 0
(9825 2950);
DISPLAY 0.617021 (9825 2950);
PAINT BLUE (9825 2950);
FORCEPROP 1 LAST TOLERANCE 5%
J 0
(10300 2950);
DISPLAY 0.617021 (10300 2950);
PAINT SKYBLUE (10300 2950);
FORCEPROP 1 LAST VALUE 0.0
J 0
(10200 2950);
DISPLAY 0.617021 (10200 2950);
PAINT SKYBLUE (10200 2950);
FORCEPROP 1 LAST PACK_TYPE 0402
J 0
(10525 2950);
DISPLAY 0.617021 (10525 2950);
PAINT SKYBLUE (10525 2950);
FORCEPROP 1 LAST MATERIAL CHIP
J 0
(10400 2950);
DISPLAY 0.617021 (10400 2950);
PAINT SKYBLUE (10400 2950);
FORCEPROP 1 LAST WATTAGE 1/16W
J 0
(10650 2950);
DISPLAY 0.617021 (10650 2950);
PAINT SKYBLUE (10650 2950);
FORCEPROP 0 LAST ROOM IO_SLOT
J 0
(10300 3100);
DISPLAY 1.021277 (10300 3100);
PAINT ORANGE (10300 3100);
DISPLAY INVISIBLE (10300 3100);
FORCEPROP 1 LAST PATH I340
J 0
(10200 3150);
DISPLAY 0.978723 (10200 3150);
PAINT WHITE (10200 3150);
DISPLAY INVISIBLE (10200 3150);
FORCEPROP 2 LAST CDS_LOCATION R1M18
J 0
(10425 2950);
DISPLAY 0.617021 (10425 2950);
PAINT AQUA (10425 2950);
DISPLAY INVISIBLE (10425 2950);
FORCEPROP 2 LAST SEC 1
J 0
(10200 3200);
DISPLAY 0.680851 (10200 3200);
PAINT MONO (10200 3200);
DISPLAY INVISIBLE (10200 3200);
FORCEPROP 2 LAST CDS_LIB mstr_discrete
J 0
(10250 3000);
PAINT ORANGE (10250 3000);
DISPLAY INVISIBLE (10250 3000);
FORCEPROP 2 LAST SEC_TYPE 0402
J 0
(10200 3200);
DISPLAY 1.021277 (10200 3200);
PAINT ORANGE (10200 3200);
DISPLAY INVISIBLE (10200 3200);
FORCEADD OFFPAGE..5
(5150 3200);
FORCEPROP 2 LAST $XR0 147 
J 0
(4895 3200);
DISPLAY 0.638298 (4895 3200);
PAINT MONO (4895 3200);
FORCEPROP 2 LAST CDS_LIB mstr_standard
J 0
(5150 3200);
PAINT ORANGE (5150 3200);
DISPLAY INVISIBLE (5150 3200);
FORCEPROP 1 LAST OFFPAGE TRUE
J 0
(5475 3075);
DISPLAY 0.872340 (5475 3075);
PAINT GREEN (5475 3075);
DISPLAY INVISIBLE (5475 3075);
FORCEPROP 1 LAST COMMENT_BODY TRUE
J 0
(5250 3125);
DISPLAY 0.872340 (5250 3125);
PAINT GREEN (5250 3125);
DISPLAY INVISIBLE (5250 3125);
FORCEPROP 2 LAST PATH I341
J 0
(5200 3275);
DISPLAY 1.021277 (5200 3275);
PAINT ORANGE (5200 3275);
DISPLAY INVISIBLE (5200 3275);
FORCEADD OFFPAGE..5
(5150 2800);
FORCEPROP 2 LAST $XR0 147 
J 0
(4895 2800);
DISPLAY 0.638298 (4895 2800);
PAINT MONO (4895 2800);
FORCEPROP 2 LAST CDS_LIB mstr_standard
J 0
(5150 2800);
PAINT ORANGE (5150 2800);
DISPLAY INVISIBLE (5150 2800);
FORCEPROP 1 LAST OFFPAGE TRUE
J 0
(5475 2675);
DISPLAY 0.872340 (5475 2675);
PAINT GREEN (5475 2675);
DISPLAY INVISIBLE (5475 2675);
FORCEPROP 1 LAST COMMENT_BODY TRUE
J 0
(5250 2725);
DISPLAY 0.872340 (5250 2725);
PAINT GREEN (5250 2725);
DISPLAY INVISIBLE (5250 2725);
FORCEPROP 2 LAST PATH I342
J 0
(5200 2875);
DISPLAY 1.021277 (5200 2875);
PAINT ORANGE (5200 2875);
DISPLAY INVISIBLE (5200 2875);
FORCEADD OFFPAGE..5
(5150 2750);
FORCEPROP 2 LAST $XR0 147 
J 0
(4895 2750);
DISPLAY 0.638298 (4895 2750);
PAINT MONO (4895 2750);
FORCEPROP 2 LAST CDS_LIB mstr_standard
J 0
(5150 2750);
PAINT ORANGE (5150 2750);
DISPLAY INVISIBLE (5150 2750);
FORCEPROP 1 LAST OFFPAGE TRUE
J 0
(5475 2625);
DISPLAY 0.872340 (5475 2625);
PAINT GREEN (5475 2625);
DISPLAY INVISIBLE (5475 2625);
FORCEPROP 1 LAST COMMENT_BODY TRUE
J 0
(5250 2675);
DISPLAY 0.872340 (5250 2675);
PAINT GREEN (5250 2675);
DISPLAY INVISIBLE (5250 2675);
FORCEPROP 2 LAST PATH I343
J 0
(5200 2825);
DISPLAY 1.021277 (5200 2825);
PAINT ORANGE (5200 2825);
DISPLAY INVISIBLE (5200 2825);
FORCEADD OFFPAGE..2
(11100 3000);
FORCEPROP 2 LAST $XR0 147 
J 0
(11289 3000);
DISPLAY 0.638298 (11289 3000);
PAINT MONO (11289 3000);
FORCEPROP 2 LAST CDS_LIB mstr_standard
J 0
(11100 3000);
PAINT ORANGE (11100 3000);
DISPLAY INVISIBLE (11100 3000);
FORCEPROP 1 LAST OFFPAGE TRUE
J 0
(11425 2875);
DISPLAY 0.872340 (11425 2875);
PAINT GREEN (11425 2875);
DISPLAY INVISIBLE (11425 2875);
FORCEPROP 1 LAST COMMENT_BODY TRUE
J 0
(11055 2905);
DISPLAY 0.872340 (11055 2905);
PAINT GREEN (11055 2905);
DISPLAY INVISIBLE (11055 2905);
FORCEPROP 2 LAST PATH I344
J 0
(11150 3075);
DISPLAY 1.021277 (11150 3075);
PAINT ORANGE (11150 3075);
DISPLAY INVISIBLE (11150 3075);
FORCEADD CAP_A..1
(10050 3950);
FORCEPROP 1 LAST VALUE 0.1UF
J 0
(10100 4000);
DISPLAY 0.617021 (10100 4000);
PAINT SKYBLUE (10100 4000);
FORCEPROP 1 LASTPIN (10050 4050) $PN 1
J 0
(10060 4030);
DISPLAY 0.617021 (10060 4030);
PAINT ORANGE (10060 4030);
FORCEPROP 1 LAST VOLTAGE 16V
J 0
(10100 3950);
DISPLAY 0.617021 (10100 3950);
PAINT SKYBLUE (10100 3950);
FORCEPROP 1 LAST TOLERANCE 10%
J 0
(10100 3900);
DISPLAY 0.617021 (10100 3900);
PAINT SKYBLUE (10100 3900);
FORCEPROP 1 LASTPIN (10050 3850) $PN 2
J 0
(10060 3830);
DISPLAY 0.617021 (10060 3830);
PAINT ORANGE (10060 3830);
FORCEPROP 1 LAST PACK_TYPE 0402V
J 0
(10100 3750);
DISPLAY 0.617021 (10100 3750);
PAINT SKYBLUE (10100 3750);
FORCEPROP 1 LAST PART_NUMBER A36096-030
J 0
(10100 3800);
DISPLAY 0.617021 (10100 3800);
PAINT BLUE (10100 3800);
FORCEPROP 1 LAST MATERIAL X7R
J 0
(10100 3850);
DISPLAY 0.617021 (10100 3850);
PAINT SKYBLUE (10100 3850);
FORCEPROP 1 LAST LOCATION C9B10
J 0
(10100 4050);
DISPLAY 0.617021 (10100 4050);
PAINT AQUA (10100 4050);
FORCEPROP 0 LAST ROOM IO_SLOT
J 0
(10100 4150);
DISPLAY 1.021277 (10100 4150);
PAINT ORANGE (10100 4150);
DISPLAY INVISIBLE (10100 4150);
FORCEPROP 2 LAST SEC_TYPE 0402V
J 0
(10100 4150);
DISPLAY 1.021277 (10100 4150);
PAINT ORANGE (10100 4150);
DISPLAY INVISIBLE (10100 4150);
FORCEPROP 2 LAST SEC 1
J 0
(10100 4150);
DISPLAY 0.680851 (10100 4150);
PAINT MONO (10100 4150);
DISPLAY INVISIBLE (10100 4150);
FORCEPROP 2 LAST CDS_LIB dev_discrete
J 0
(10050 3950);
PAINT ORANGE (10050 3950);
DISPLAY INVISIBLE (10050 3950);
FORCEPROP 1 LAST PATH I345
J 0
(10100 4100);
DISPLAY 0.978723 (10100 4100);
PAINT WHITE (10100 4100);
DISPLAY INVISIBLE (10100 4100);
FORCEADD GND..1
(10050 3600);
FORCEPROP 3 LASTPIN (10050 3650) SIG_NAME GND\g
J 0
(10060 3660);
DISPLAY 0.659574 (10060 3660);
PAINT MONO (10060 3660);
DISPLAY INVISIBLE (10060 3660);
FORCEPROP 1 LAST VOLTAGE 0
J 0
(10050 3600);
PAINT SKYBLUE (10050 3600);
DISPLAY INVISIBLE (10050 3600);
FORCEPROP 1 LAST HDL_POWER GND
J 0
(10050 3750);
DISPLAY 0.872340 (10050 3750);
PAINT GREEN (10050 3750);
DISPLAY INVISIBLE (10050 3750);
FORCEPROP 2 LAST CDS_LIB mstr_symbols
J 0
(10050 3600);
PAINT ORANGE (10050 3600);
DISPLAY INVISIBLE (10050 3600);
FORCEPROP 1 LAST PATH I346
J 0
(10125 3600);
DISPLAY 0.872340 (10125 3600);
PAINT AQUA (10125 3600);
DISPLAY INVISIBLE (10125 3600);
FORCEPROP 1 LAST BODY_TYPE PLUMBING
J 0
(10005 3557);
DISPLAY 0.340426 (10005 3557);
PAINT GREEN (10005 3557);
DISPLAY INVISIBLE (10005 3557);
FORCEPROP 1 LAST SIZE 1B
J 0
(10125 3550);
DISPLAY 0.872340 (10125 3550);
PAINT AQUA (10125 3550);
DISPLAY INVISIBLE (10125 3550);
FORCEADD P5V_STBY..1
(9650 4300);
FORCEPROP 3 LASTPIN (9650 4250) SIG_NAME P5V_STBY\g
J 0
(9660 4260);
DISPLAY 0.659574 (9660 4260);
PAINT MONO (9660 4260);
DISPLAY INVISIBLE (9660 4260);
FORCEPROP 1 LAST VOLTAGE 5.0V
J 0
(9605 4257);
DISPLAY 0.340426 (9605 4257);
PAINT SKYBLUE (9605 4257);
DISPLAY INVISIBLE (9605 4257);
FORCEPROP 1 LAST HDL_POWER P5V_STBY
J 0
(9350 4175);
DISPLAY 0.872340 (9350 4175);
PAINT ORANGE (9350 4175);
DISPLAY INVISIBLE (9350 4175);
FORCEPROP 2 LAST CDS_LIB mstr_symbols
J 0
(9650 4300);
PAINT ORANGE (9650 4300);
DISPLAY INVISIBLE (9650 4300);
FORCEPROP 1 LAST PATH I348
J 0
(9695 4302);
DISPLAY 0.340426 (9695 4302);
PAINT GREEN (9695 4302);
DISPLAY INVISIBLE (9695 4302);
FORCEPROP 1 LAST BODY_TYPE PLUMBING
J 0
(9605 4257);
DISPLAY 0.340426 (9605 4257);
PAINT GREEN (9605 4257);
DISPLAY INVISIBLE (9605 4257);
FORCEPROP 1 LAST SIZE 1B
J 0
(9695 4322);
DISPLAY 0.340426 (9695 4322);
PAINT GREEN (9695 4322);
DISPLAY INVISIBLE (9695 4322);
FORCEADD P3V3_STBY..1
(6300 4250);
FORCEPROP 3 LASTPIN (6300 4200) SIG_NAME P3V3_STBY\g
J 0
(6310 4210);
DISPLAY 0.659574 (6310 4210);
PAINT MONO (6310 4210);
DISPLAY INVISIBLE (6310 4210);
FORCEPROP 1 LAST SIZE 1B
J 0
(6345 4272);
DISPLAY 0.340426 (6345 4272);
PAINT GREEN (6345 4272);
DISPLAY INVISIBLE (6345 4272);
FORCEPROP 1 LAST BODY_TYPE PLUMBING
J 0
(6255 4207);
DISPLAY 0.340426 (6255 4207);
PAINT GREEN (6255 4207);
DISPLAY INVISIBLE (6255 4207);
FORCEPROP 1 LAST HDL_POWER P3V3_STBY
J 0
(6000 4125);
DISPLAY 0.872340 (6000 4125);
PAINT ORANGE (6000 4125);
DISPLAY INVISIBLE (6000 4125);
FORCEPROP 1 LAST VOLTAGE 3.3V
J 0
(6255 4207);
DISPLAY 0.340426 (6255 4207);
PAINT SKYBLUE (6255 4207);
DISPLAY INVISIBLE (6255 4207);
FORCEPROP 1 LAST PATH I350
J 0
(6345 4252);
DISPLAY 0.340426 (6345 4252);
PAINT GREEN (6345 4252);
DISPLAY INVISIBLE (6345 4252);
FORCEPROP 2 LAST CDS_LIB mstr_symbols
J 0
(6300 4250);
PAINT MONO (6300 4250);
DISPLAY INVISIBLE (6300 4250);
FORCEADD OFFPAGE..2
(9900 900);
FORCEPROP 2 LAST $XR0 250 
J 0
(10089 900);
DISPLAY 0.638298 (10089 900);
PAINT MONO (10089 900);
FORCEPROP 2 LAST CDS_LIB mstr_standard
J 0
(9900 900);
PAINT ORANGE (9900 900);
DISPLAY INVISIBLE (9900 900);
FORCEPROP 1 LAST OFFPAGE TRUE
J 0
(10225 775);
DISPLAY 0.872340 (10225 775);
PAINT GREEN (10225 775);
DISPLAY INVISIBLE (10225 775);
FORCEPROP 1 LAST COMMENT_BODY TRUE
J 0
(9855 805);
DISPLAY 0.872340 (9855 805);
PAINT GREEN (9855 805);
DISPLAY INVISIBLE (9855 805);
FORCEPROP 2 LAST PATH I354
J 0
(10350 950);
DISPLAY 1.021277 (10350 950);
PAINT ORANGE (10350 950);
DISPLAY INVISIBLE (10350 950);
FORCEADD RES..2
(6300 4000);
FORCEPROP 1 LAST PACK_TYPE 0402
J 0
(6390 3875);
DISPLAY 0.617021 (6390 3875);
PAINT SKYBLUE (6390 3875);
FORCEPROP 1 LAST MATERIAL CHIP
J 0
(6390 3925);
DISPLAY 0.617021 (6390 3925);
PAINT SKYBLUE (6390 3925);
FORCEPROP 1 LAST WATTAGE 1/16W
J 0
(6390 3975);
DISPLAY 0.617021 (6390 3975);
PAINT SKYBLUE (6390 3975);
FORCEPROP 1 LAST TOLERANCE 1%
J 0
(6395 4025);
DISPLAY 0.617021 (6395 4025);
PAINT SKYBLUE (6395 4025);
FORCEPROP 1 LAST VALUE 10.0K
J 0
(6395 4075);
DISPLAY 0.617021 (6395 4075);
PAINT SKYBLUE (6395 4075);
FORCEPROP 1 LASTPIN (6300 4100) $PN 1
J 0
(6305 4062);
DISPLAY 0.787234 (6305 4062);
PAINT ORANGE (6305 4062);
FORCEPROP 1 LAST PART_NUMBER G21796-016
R 1
J 0
(6240 3875);
DISPLAY 0.617021 (6240 3875);
PAINT BLUE (6240 3875);
FORCEPROP 1 LASTPIN (6300 3900) $PN 2
J 0
(6305 3910);
DISPLAY 0.787234 (6305 3910);
PAINT ORANGE (6305 3910);
FORCEPROP 1 LAST LOCATION R9W1
J 0
(6395 4125);
DISPLAY 0.617021 (6395 4125);
PAINT AQUA (6395 4125);
FORCEPROP 2 LAST CDS_LIB mstr_discrete
J 0
(6300 4000);
PAINT MONO (6300 4000);
DISPLAY INVISIBLE (6300 4000);
FORCEPROP 1 LAST PATH I356
J 0
(6350 4175);
DISPLAY 0.978723 (6350 4175);
PAINT WHITE (6350 4175);
DISPLAY INVISIBLE (6350 4175);
FORCEPROP 2 LAST ROOM CPU0
J 0
(6325 3775);
PAINT WHITE (6325 3775);
DISPLAY INVISIBLE (6325 3775);
FORCEPROP 2 LAST BOM_COST PROC_SIDEBAND
J 0
(6300 4000);
PAINT WHITE (6300 4000);
DISPLAY INVISIBLE (6300 4000);
FORCEPROP 0 LAST SEC 1
J 0
(6400 4175);
DISPLAY 0.680851 (6400 4175);
PAINT MONO (6400 4175);
DISPLAY INVISIBLE (6400 4175);
FORCEPROP 2 LAST SEC_TYPE 0402
J 0
(6350 4225);
DISPLAY 1.021277 (6350 4225);
PAINT ORANGE (6350 4225);
DISPLAY INVISIBLE (6350 4225);
FORCEADD SC1U10V2KX-4-GP..1
(9650 3925);
FORCEPROP 2 LASTPIN (9650 3850) $PN 2
R 1
J 2
(9640 3840);
DISPLAY 0.808511 (9640 3840);
PAINT ORANGE (9640 3840);
FORCEPROP 2 LAST RATED 10V
J 0
(9750 3850);
DISPLAY 0.638298 (9750 3850);
PAINT GREEN (9750 3850);
FORCEPROP 2 LAST TOLERANCE 10%
J 0
(9750 3900);
DISPLAY 0.638298 (9750 3900);
PAINT GREEN (9750 3900);
FORCEPROP 2 LAST ATTRIBUTE 1UF
J 0
(9750 3950);
DISPLAY 0.638298 (9750 3950);
PAINT GREEN (9750 3950);
FORCEPROP 2 LAST PACK_SIZE 0402
J 0
(9750 3800);
DISPLAY 0.638298 (9750 3800);
PAINT GREEN (9750 3800);
FORCEPROP 1 LAST LOCATION C9B9
J 0
(9750 4005);
DISPLAY 0.617021 (9750 4005);
PAINT GREEN (9750 4005);
FORCEPROP 2 LASTPIN (9650 4000) $PN 1
R 1
J 0
(9640 4010);
DISPLAY 0.808511 (9640 4010);
PAINT ORANGE (9640 4010);
FORCEPROP 1 LAST VALUE SC1U10V2KX-4-GP
R 1
J 0
(9725 3725);
DISPLAY 0.617021 (9725 3725);
PAINT GREEN (9725 3725);
FORCEPROP 1 LAST CDS_LMAN_SYM_OUTLINE -50,25,50,-25
J 0
(9650 3925);
DISPLAY 0.468085 (9650 3925);
PAINT GREEN (9650 3925);
DISPLAY INVISIBLE (9650 3925);
FORCEPROP 1 LAST PATH I357
J 0
(9650 3925);
DISPLAY 0.617021 (9650 3925);
PAINT GREEN (9650 3925);
DISPLAY INVISIBLE (9650 3925);
FORCEPROP 2 LAST CDS_LIB w_hdl
J 0
(9650 3925);
PAINT MONO (9650 3925);
DISPLAY INVISIBLE (9650 3925);
FORCEPROP 1 LAST PART_NUMBER 78.10523.8FL
J 0
(9650 3925);
DISPLAY 0.617021 (9650 3925);
PAINT GREEN (9650 3925);
DISPLAY INVISIBLE (9650 3925);
FORCEPROP 2 LAST SEC_TYPE SMD-BCG6
J 0
(9675 4000);
DISPLAY 1.021277 (9675 4000);
PAINT ORANGE (9675 4000);
DISPLAY INVISIBLE (9675 4000);
FORCEPROP 2 LAST SEC 1
J 0
(9675 4000);
DISPLAY 0.680851 (9675 4000);
PAINT MONO (9675 4000);
DISPLAY INVISIBLE (9675 4000);
FORCEPROP 1 LAST PACK_TYPE SMD-BCG6
J 0
(9650 3925);
DISPLAY 0.617021 (9650 3925);
PAINT GREEN (9650 3925);
DISPLAY INVISIBLE (9650 3925);
FORCEADD 887R2F-L-GP..1
(6300 3675);
FORCEPROP 2 LAST PACK_SIZE 0402
J 0
(6325 3525);
DISPLAY 0.638298 (6325 3525);
PAINT GREEN (6325 3525);
FORCEPROP 1 LAST LOCATION R9B7
J 0
(6325 3775);
DISPLAY 0.617021 (6325 3775);
PAINT GREEN (6325 3775);
FORCEPROP 2 LAST RATED 1/16W
J 0
(6325 3575);
DISPLAY 0.638298 (6325 3575);
PAINT GREEN (6325 3575);
FORCEPROP 2 LAST TOLERANCE 1%
J 0
(6325 3625);
DISPLAY 0.638298 (6325 3625);
PAINT GREEN (6325 3625);
FORCEPROP 1 LAST VALUE 887R2F-L-GP
J 0
(6325 3725);
DISPLAY 0.617021 (6325 3725);
PAINT GREEN (6325 3725);
FORCEPROP 2 LASTPIN (6300 3550) $PN 2
R 1
J 2
(6290 3540);
DISPLAY 0.808511 (6290 3540);
PAINT ORANGE (6290 3540);
FORCEPROP 2 LASTPIN (6300 3800) $PN 1
R 1
J 0
(6290 3810);
DISPLAY 0.808511 (6290 3810);
PAINT ORANGE (6290 3810);
FORCEPROP 2 LAST ATTRIBUTE 887OHM
J 0
(6325 3675);
DISPLAY 0.638298 (6325 3675);
PAINT GREEN (6325 3675);
FORCEPROP 1 LAST PATH I358
J 0
(6300 3675);
DISPLAY 0.617021 (6300 3675);
PAINT GREEN (6300 3675);
DISPLAY INVISIBLE (6300 3675);
FORCEPROP 1 LAST PACK_TYPE SMD-RG
J 0
(6300 3675);
DISPLAY 0.617021 (6300 3675);
PAINT GREEN (6300 3675);
DISPLAY INVISIBLE (6300 3675);
FORCEPROP 2 LAST SEC 1
J 0
(6325 3825);
DISPLAY 0.680851 (6325 3825);
PAINT MONO (6325 3825);
DISPLAY INVISIBLE (6325 3825);
FORCEPROP 2 LAST SEC_TYPE SMD-RG
J 0
(6325 3825);
DISPLAY 1.021277 (6325 3825);
PAINT ORANGE (6325 3825);
DISPLAY INVISIBLE (6325 3825);
FORCEPROP 1 LAST PART_NUMBER 64.88705.6DL
J 0
(6300 3675);
DISPLAY 0.617021 (6300 3675);
PAINT GREEN (6300 3675);
DISPLAY INVISIBLE (6300 3675);
FORCEPROP 2 LAST CDS_LIB w_hdl
J 0
(6300 3675);
DISPLAY INVISIBLE (6300 3675);
FORCEPROP 1 LAST CDS_LMAN_SYM_OUTLINE -50,75,50,-75
J 0
(6300 3675);
DISPLAY 0.468085 (6300 3675);
PAINT GREEN (6300 3675);
DISPLAY INVISIBLE (6300 3675);
FORCEADD CAP..1
(10850 3950);
FORCEPROP 1 LAST VOLTAGE 16V
J 0
(10900 3950);
DISPLAY 0.617021 (10900 3950);
PAINT SKYBLUE (10900 3950);
FORCEPROP 1 LAST TOLERANCE 10%
J 0
(10900 3900);
DISPLAY 0.617021 (10900 3900);
PAINT SKYBLUE (10900 3900);
FORCEPROP 1 LAST PART_NUMBER C95333-007
J 0
(10900 3800);
DISPLAY 0.617021 (10900 3800);
PAINT BLUE (10900 3800);
FORCEPROP 1 LAST PACK_TYPE 0805
J 0
(10900 3750);
DISPLAY 0.617021 (10900 3750);
PAINT SKYBLUE (10900 3750);
FORCEPROP 1 LAST MATERIAL X6S
J 0
(10900 3850);
DISPLAY 0.617021 (10900 3850);
PAINT SKYBLUE (10900 3850);
FORCEPROP 1 LASTPIN (10850 4050) $PN 1
J 0
(10860 4030);
DISPLAY 0.617021 (10860 4030);
PAINT ORANGE (10860 4030);
FORCEPROP 1 LASTPIN (10850 3850) $PN 2
J 0
(10860 3830);
DISPLAY 0.617021 (10860 3830);
PAINT ORANGE (10860 3830);
FORCEPROP 1 LAST LOCATION C1M26
J 0
(10900 4050);
DISPLAY 0.617021 (10900 4050);
PAINT AQUA (10900 4050);
FORCEPROP 1 LAST VALUE 10UF
J 0
(10900 4000);
DISPLAY 0.617021 (10900 4000);
PAINT SKYBLUE (10900 4000);
FORCEPROP 0 LAST ROOM IO_SLOT
J 0
(10900 4150);
DISPLAY 1.021277 (10900 4150);
PAINT ORANGE (10900 4150);
DISPLAY INVISIBLE (10900 4150);
FORCEPROP 1 LAST PATH I6
J 0
(10900 4100);
DISPLAY 0.978723 (10900 4100);
PAINT WHITE (10900 4100);
DISPLAY INVISIBLE (10900 4100);
FORCEPROP 2 LAST CDS_LOCATION C1M26
J 0
(10900 4050);
DISPLAY 0.617021 (10900 4050);
PAINT AQUA (10900 4050);
DISPLAY INVISIBLE (10900 4050);
FORCEPROP 2 LAST SEC 1
J 0
(10900 4150);
DISPLAY 0.680851 (10900 4150);
PAINT MONO (10900 4150);
DISPLAY INVISIBLE (10900 4150);
FORCEPROP 2 LAST CDS_LIB mstr_discrete
J 0
(10850 3950);
PAINT ORANGE (10850 3950);
DISPLAY INVISIBLE (10850 3950);
FORCEPROP 2 LAST SEC_TYPE 0805
J 0
(10900 4150);
DISPLAY 1.021277 (10900 4150);
PAINT ORANGE (10900 4150);
DISPLAY INVISIBLE (10900 4150);
FORCEADD CAP_A..1
(11225 3950);
FORCEPROP 1 LAST PACK_TYPE 0402V
J 0
(11275 3750);
DISPLAY 0.617021 (11275 3750);
PAINT SKYBLUE (11275 3750);
FORCEPROP 1 LAST VOLTAGE 16V
J 0
(11275 3950);
DISPLAY 0.617021 (11275 3950);
PAINT SKYBLUE (11275 3950);
FORCEPROP 1 LASTPIN (11225 4050) $PN 1
J 0
(11235 4030);
DISPLAY 0.617021 (11235 4030);
PAINT ORANGE (11235 4030);
FORCEPROP 1 LAST VALUE 0.1UF
J 0
(11275 4000);
DISPLAY 0.617021 (11275 4000);
PAINT SKYBLUE (11275 4000);
FORCEPROP 1 LAST LOCATION C1M23
J 0
(11275 4050);
DISPLAY 0.617021 (11275 4050);
PAINT AQUA (11275 4050);
FORCEPROP 1 LASTPIN (11225 3850) $PN 2
J 0
(11235 3830);
DISPLAY 0.617021 (11235 3830);
PAINT ORANGE (11235 3830);
FORCEPROP 1 LAST MATERIAL X7R
J 0
(11275 3850);
DISPLAY 0.617021 (11275 3850);
PAINT SKYBLUE (11275 3850);
FORCEPROP 1 LAST PART_NUMBER A36096-030
J 0
(11275 3800);
DISPLAY 0.617021 (11275 3800);
PAINT BLUE (11275 3800);
FORCEPROP 1 LAST TOLERANCE 10%
J 0
(11275 3900);
DISPLAY 0.617021 (11275 3900);
PAINT SKYBLUE (11275 3900);
FORCEPROP 0 LAST ROOM IO_SLOT
J 0
(11275 4150);
DISPLAY 1.021277 (11275 4150);
PAINT ORANGE (11275 4150);
DISPLAY INVISIBLE (11275 4150);
FORCEPROP 2 LAST SEC 1
J 0
(11275 4150);
DISPLAY 0.680851 (11275 4150);
PAINT MONO (11275 4150);
DISPLAY INVISIBLE (11275 4150);
FORCEPROP 2 LAST SEC_TYPE 0402V
J 0
(11275 4150);
DISPLAY 1.021277 (11275 4150);
PAINT ORANGE (11275 4150);
DISPLAY INVISIBLE (11275 4150);
FORCEPROP 2 LAST CDS_SEC 1
J 0
(11275 4100);
PAINT ORANGE (11275 4100);
DISPLAY INVISIBLE (11275 4100);
FORCEPROP 2 LAST CDS_LIB dev_discrete
J 0
(11225 3950);
PAINT ORANGE (11225 3950);
DISPLAY INVISIBLE (11225 3950);
FORCEPROP 2 LAST CDS_LOCATION C1M23
J 0
(11275 4050);
DISPLAY 0.617021 (11275 4050);
PAINT AQUA (11275 4050);
DISPLAY INVISIBLE (11275 4050);
FORCEPROP 1 LAST PATH I7
J 0
(11275 4100);
DISPLAY 0.978723 (11275 4100);
PAINT WHITE (11275 4100);
DISPLAY INVISIBLE (11275 4100);
FORCEADD CAP_A..1
(11650 3950);
FORCEPROP 1 LAST PACK_TYPE 0402V
J 0
(11700 3750);
DISPLAY 0.617021 (11700 3750);
PAINT SKYBLUE (11700 3750);
FORCEPROP 1 LAST PART_NUMBER A36096-030
J 0
(11700 3800);
DISPLAY 0.617021 (11700 3800);
PAINT BLUE (11700 3800);
FORCEPROP 1 LAST LOCATION C1M22
J 0
(11700 4050);
DISPLAY 0.617021 (11700 4050);
PAINT AQUA (11700 4050);
FORCEPROP 1 LAST TOLERANCE 10%
J 0
(11700 3900);
DISPLAY 0.617021 (11700 3900);
PAINT SKYBLUE (11700 3900);
FORCEPROP 1 LAST VOLTAGE 16V
J 0
(11700 3950);
DISPLAY 0.617021 (11700 3950);
PAINT SKYBLUE (11700 3950);
FORCEPROP 1 LAST MATERIAL X7R
J 0
(11700 3850);
DISPLAY 0.617021 (11700 3850);
PAINT SKYBLUE (11700 3850);
FORCEPROP 1 LASTPIN (11650 4050) $PN 1
J 0
(11660 4030);
DISPLAY 0.617021 (11660 4030);
PAINT ORANGE (11660 4030);
FORCEPROP 1 LASTPIN (11650 3850) $PN 2
J 0
(11660 3830);
DISPLAY 0.617021 (11660 3830);
PAINT ORANGE (11660 3830);
FORCEPROP 1 LAST VALUE 0.1UF
J 0
(11700 4000);
DISPLAY 0.617021 (11700 4000);
PAINT SKYBLUE (11700 4000);
FORCEPROP 0 LAST ROOM IO_SLOT
J 0
(11700 4150);
DISPLAY 1.021277 (11700 4150);
PAINT ORANGE (11700 4150);
DISPLAY INVISIBLE (11700 4150);
FORCEPROP 2 LAST SEC 1
J 0
(11700 4150);
DISPLAY 0.680851 (11700 4150);
PAINT MONO (11700 4150);
DISPLAY INVISIBLE (11700 4150);
FORCEPROP 2 LAST SEC_TYPE 0402V
J 0
(11700 4150);
DISPLAY 1.021277 (11700 4150);
PAINT ORANGE (11700 4150);
DISPLAY INVISIBLE (11700 4150);
FORCEPROP 2 LAST CDS_SEC 1
J 0
(11700 4100);
PAINT ORANGE (11700 4100);
DISPLAY INVISIBLE (11700 4100);
FORCEPROP 2 LAST CDS_LIB dev_discrete
J 0
(11650 3950);
PAINT ORANGE (11650 3950);
DISPLAY INVISIBLE (11650 3950);
FORCEPROP 2 LAST CDS_LOCATION C1M22
J 0
(11700 4050);
DISPLAY 0.617021 (11700 4050);
PAINT AQUA (11700 4050);
DISPLAY INVISIBLE (11700 4050);
FORCEPROP 1 LAST PATH I8
J 0
(11700 4100);
DISPLAY 0.978723 (11700 4100);
PAINT WHITE (11700 4100);
DISPLAY INVISIBLE (11700 4100);
FORCEADD GND..1
(10850 4275);
FORCEPROP 3 LASTPIN (10850 4325) SIG_NAME GND\g
J 0
(10860 4335);
DISPLAY 0.659574 (10860 4335);
PAINT MONO (10860 4335);
DISPLAY INVISIBLE (10860 4335);
FORCEPROP 1 LAST VOLTAGE 0
J 0
(10850 4275);
PAINT SKYBLUE (10850 4275);
DISPLAY INVISIBLE (10850 4275);
FORCEPROP 1 LAST HDL_POWER GND
J 0
(10850 4425);
DISPLAY 0.872340 (10850 4425);
PAINT GREEN (10850 4425);
DISPLAY INVISIBLE (10850 4425);
FORCEPROP 1 LAST PATH I9
J 0
(10925 4275);
DISPLAY 0.872340 (10925 4275);
PAINT AQUA (10925 4275);
DISPLAY INVISIBLE (10925 4275);
FORCEPROP 1 LAST BODY_TYPE PLUMBING
J 0
(10805 4232);
DISPLAY 0.340426 (10805 4232);
PAINT GREEN (10805 4232);
DISPLAY INVISIBLE (10805 4232);
FORCEPROP 2 LAST CDS_LIB mstr_symbols
J 0
(10850 4275);
PAINT MONO (10850 4275);
DISPLAY INVISIBLE (10850 4275);
FORCEPROP 1 LAST SIZE 1B
J 0
(10925 4225);
DISPLAY 0.872340 (10925 4225);
PAINT AQUA (10925 4225);
DISPLAY INVISIBLE (10925 4225);
FORCEADD DESIGN_NOTE..1
(9300 4800);
FORCEPROP 0 LAST L2 12MM HT CONNECTOR IN BOM
J 0
(9100 4600);
DISPLAY 1.021277 (9100 4600);
PAINT ORANGE (9100 4600);
FORCEPROP 0 LAST L1 13MM HT CONNECTOR IN SCHEMATIC
J 0
(9100 4675);
DISPLAY 1.021277 (9100 4675);
PAINT ORANGE (9100 4675);
FORCEPROP 1 LAST COMMENT_BODY TRUE
J 0
(9325 4900);
DISPLAY 0.978723 (9325 4900);
PAINT ORANGE (9325 4900);
DISPLAY INVISIBLE (9325 4900);
FORCEPROP 2 LAST CDS_LIB mstr_symbols
J 0
(9300 4800);
PAINT ORANGE (9300 4800);
DISPLAY INVISIBLE (9300 4800);
FORCEADD CAD_NOTE..1
(4350 3875);
FORCEPROP 0 LAST L3 RMII_BMC_OCP_CRSDV_R
J 0
(4200 3600);
DISPLAY 1.021277 (4200 3600);
PAINT ORANGE (4200 3600);
FORCEPROP 0 LAST L4 RMII_BMC_OCP_RXD0_R
J 0
(4200 3525);
DISPLAY 1.021277 (4200 3525);
PAINT ORANGE (4200 3525);
FORCEPROP 0 LAST L6 RMII_BMC_OCP_RXER_R
J 0
(4200 3375);
DISPLAY 1.021277 (4200 3375);
PAINT ORANGE (4200 3375);
FORCEPROP 0 LAST L5 RMII_BMC_OCP_RXD1_R
J 0
(4200 3450);
DISPLAY 1.021277 (4200 3450);
PAINT ORANGE (4200 3450);
FORCEPROP 0 LAST L1 PLACE SERIES RESISTORS ON THE FOLLOWING
J 0
(4200 3750);
DISPLAY 1.021277 (4200 3750);
PAINT ORANGE (4200 3750);
FORCEPROP 0 LAST L2 NETS WITHIN 2 INCHES OF THE OCP CONNECTOR:
J 0
(4200 3675);
DISPLAY 1.021277 (4200 3675);
PAINT ORANGE (4200 3675);
FORCEPROP 1 LAST COMMENT_BODY TRUE
J 0
(4375 3975);
DISPLAY 0.978723 (4375 3975);
PAINT ORANGE (4375 3975);
DISPLAY INVISIBLE (4375 3975);
FORCEPROP 2 LAST CDS_LIB mstr_symbols
J 0
(4350 3875);
PAINT ORANGE (4350 3875);
DISPLAY INVISIBLE (4350 3875);
FORCEADD INTEL_CORP_BPAGE..1
(12075 200);
FORCEPROP 1 LAST CDS_CON_LAST_MODIFIED Fri Jun 16 17:49:08 2017
J 0
(10650 525);
PAINT ORANGE (10650 525);
DISPLAY INVISIBLE (10650 525);
FORCEPROP 1 LAST CUSTOM_TXT_CDS <CURRENT_DESIGN_SHEET> OF <TOTAL_DESIGN_SHEETS>
J 0
(11575 225);
PAINT ORANGE (11575 225);
FORCEPROP 1 LAST CUSTOM_TXT_CDS <CON_LAST_MODIFIED>
J 0
(8075 300);
PAINT ORANGE (8075 300);
FORCEPROP 2 LAST CUSTOM_TXT_CDS <XR_PAGE_TITLE>
J 0
(4185 5450);
DISPLAY 0.638298 (4185 5450);
PAINT PINK (4185 5450);
DISPLAY INVISIBLE (4185 5450);
FORCEPROP 1 LAST SCH_TITLE OCP MODULE CONN A
J 0
(4125 250);
DISPLAY 1.212766 (4125 250);
PAINT ORANGE (4125 250);
FORCEPROP 2 LAST PAGE_BORDER TRUE
J 0
(4185 5450);
DISPLAY 0.638298 (4185 5450);
PAINT PINK (4185 5450);
DISPLAY INVISIBLE (4185 5450);
FORCEPROP 2 LAST CDS_LIB mstr_symbols
J 0
(12075 200);
PAINT MONO (12075 200);
DISPLAY INVISIBLE (12075 200);
FORCEPROP 1 LAST COMMENT_BODY TRUE
J 0
(12087 212);
DISPLAY 0.468085 (12087 212);
PAINT GREEN (12087 212);
DISPLAY INVISIBLE (12087 212);
FORCEPROP 2 LAST CDS_XR_PAGE_TITLE CR-186 : @BASEBOARD_FAB2_LIB.BASEBOARD_FAB2(SCH_1):PAGE186
J 0
(4185 5450);
DISPLAY 0.638298 (4185 5450);
PAINT PINK (4185 5450);
DISPLAY INVISIBLE (4185 5450);
WIRE 16 -1 (11650 3700)(11650 3600);
WIRE 16 -1 (11225 3700)(11650 3700);
WIRE 16 -1 (11650 3850)(11650 3700);
WIRE 16 -1 (10850 3700)(11225 3700);
WIRE 16 -1 (11225 3700)(11225 3850);
WIRE 16 -1 (10450 3700)(10850 3700);
WIRE 16 -1 (10850 3700)(10850 3850);
WIRE 16 -1 (10450 3875)(10450 3700);
WIRE 16 -1 (7525 750)(7525 900);
WIRE 16 -1 (7525 900)(7525 1050);
WIRE 16 -1 (7850 900)(7525 900);
WIRE 16 -1 (7525 1050)(7525 1100);
WIRE 16 -1 (7850 1050)(7525 1050);
WIRE 16 -1 (7525 1100)(7525 1250);
WIRE 16 -1 (7850 1100)(7525 1100);
WIRE 16 -1 (7525 1250)(7525 1300);
WIRE 16 -1 (7850 1250)(7525 1250);
WIRE 16 -1 (7525 1300)(7525 1450);
WIRE 16 -1 (7850 1300)(7525 1300);
WIRE 16 -1 (7525 1450)(7525 1500);
WIRE 16 -1 (7850 1450)(7525 1450);
WIRE 16 -1 (7525 1500)(7525 1650);
WIRE 16 -1 (7850 1500)(7525 1500);
WIRE 16 -1 (7525 1650)(7525 1700);
WIRE 16 -1 (7850 1650)(7525 1650);
WIRE 16 -1 (7525 1700)(7525 1850);
WIRE 16 -1 (7850 1700)(7525 1700);
WIRE 16 -1 (7525 1850)(7525 1900);
WIRE 16 -1 (7850 1850)(7525 1850);
WIRE 16 -1 (7525 2050)(7525 1900);
WIRE 16 -1 (7850 1900)(7525 1900);
WIRE 16 -1 (7525 2100)(7525 2050);
WIRE 16 -1 (7850 2050)(7525 2050);
WIRE 16 -1 (7525 2250)(7525 2100);
WIRE 16 -1 (7850 2100)(7525 2100);
WIRE 16 -1 (7525 2250)(7525 2300);
WIRE 16 -1 (7850 2250)(7525 2250);
WIRE 16 -1 (7525 2300)(7525 2450);
WIRE 16 -1 (7850 2300)(7525 2300);
WIRE 16 -1 (7525 2450)(7525 2500);
WIRE 16 -1 (7850 2450)(7525 2450);
WIRE 16 -1 (7525 2500)(7525 2650);
WIRE 16 -1 (7850 2500)(7525 2500);
WIRE 16 -1 (7525 2650)(7525 2700);
WIRE 16 -1 (7850 2650)(7525 2650);
WIRE 16 -1 (7525 2700)(7525 2850);
WIRE 16 -1 (7850 2700)(7525 2700);
WIRE 16 -1 (7525 2850)(7525 2900);
WIRE 16 -1 (7850 2850)(7525 2850);
WIRE 16 -1 (7525 2900)(7525 3450);
WIRE 16 -1 (7850 2900)(7525 2900);
WIRE 16 -1 (7525 3500)(7525 3450);
WIRE 16 -1 (7850 3450)(7525 3450);
WIRE 16 -1 (7525 3600)(7525 3500);
WIRE 16 -1 (7850 3500)(7525 3500);
WIRE 16 -1 (7525 3650)(7525 3600);
WIRE 16 -1 (7850 3600)(7525 3600);
WIRE 16 -1 (7850 3650)(7525 3650);
WIRE 16 -1 (8975 775)(8975 950);
WIRE 16 -1 (8975 950)(8975 1000);
WIRE 16 -1 (8650 950)(8975 950);
WIRE 16 -1 (8975 1000)(8975 1150);
WIRE 16 -1 (8650 1000)(8975 1000);
WIRE 16 -1 (8975 1150)(8975 1200);
WIRE 16 -1 (8650 1150)(8975 1150);
WIRE 16 -1 (8975 1200)(8975 1350);
WIRE 16 -1 (8650 1200)(8975 1200);
WIRE 16 -1 (8975 1350)(8975 1400);
WIRE 16 -1 (8650 1350)(8975 1350);
WIRE 16 -1 (8975 1400)(8975 1550);
WIRE 16 -1 (8650 1400)(8975 1400);
WIRE 16 -1 (8975 1550)(8975 1600);
WIRE 16 -1 (8650 1550)(8975 1550);
WIRE 16 -1 (8975 1600)(8975 1750);
WIRE 16 -1 (8650 1600)(8975 1600);
WIRE 16 -1 (8975 1750)(8975 1800);
WIRE 16 -1 (8650 1750)(8975 1750);
WIRE 16 -1 (8975 1800)(8975 1950);
WIRE 16 -1 (8650 1800)(8975 1800);
WIRE 16 -1 (8975 1950)(8975 2000);
WIRE 16 -1 (8650 1950)(8975 1950);
WIRE 16 -1 (8975 2000)(8975 2150);
WIRE 16 -1 (8650 2000)(8975 2000);
WIRE 16 -1 (8975 2150)(8975 2200);
WIRE 16 -1 (8650 2150)(8975 2150);
WIRE 16 -1 (8975 2200)(8975 2350);
WIRE 16 -1 (8650 2200)(8975 2200);
WIRE 16 -1 (8975 2350)(8975 2400);
WIRE 16 -1 (8650 2350)(8975 2350);
WIRE 16 -1 (8975 2400)(8975 2550);
WIRE 16 -1 (8650 2400)(8975 2400);
WIRE 16 -1 (8975 2550)(8975 2600);
WIRE 16 -1 (8650 2550)(8975 2550);
WIRE 16 -1 (8975 2600)(8975 2750);
WIRE 16 -1 (8650 2600)(8975 2600);
WIRE 16 -1 (8975 2750)(8975 2800);
WIRE 16 -1 (8650 2750)(8975 2750);
WIRE 16 -1 (8975 2800)(8975 2950);
WIRE 16 -1 (8650 2800)(8975 2800);
WIRE 16 -1 (8975 2950)(8975 3250);
WIRE 16 -1 (8650 2950)(8975 2950);
WIRE 16 -1 (8975 3250)(8975 3500);
WIRE 16 -1 (8650 3250)(8975 3250);
WIRE 16 -1 (8975 3550)(8975 3500);
WIRE 16 -1 (8650 3500)(8975 3500);
WIRE 16 -1 (8975 3650)(8975 3550);
WIRE 16 -1 (8650 3550)(8975 3550);
WIRE 16 -1 (8975 3700)(8975 3650);
WIRE 16 -1 (8650 3650)(8975 3650);
WIRE 16 -1 (8650 3700)(8975 3700);
WIRE 16 -1 (7000 3400)(7000 3450);
WIRE 16 -1 (7000 3350)(7000 3400);
WIRE 16 -1 (7850 3400)(7000 3400);
WIRE 16 -1 (7000 3300)(7000 3350);
WIRE 16 -1 (7850 3350)(7000 3350);
WIRE 16 -1 (7000 3250)(7000 3300);
WIRE 16 -1 (7850 3300)(7000 3300);
WIRE 16 -1 (7850 3250)(7000 3250);
WIRE 16 -1 (6300 3500)(6300 3550);
WIRE 16 -1 (8850 4000)(8850 3450);
WIRE 16 -1 (8850 3450)(8850 3400);
WIRE 16 -1 (8850 3450)(8650 3450);
WIRE 16 -1 (8850 3400)(8850 3350);
WIRE 16 -1 (8850 3400)(8650 3400);
WIRE 16 -1 (8850 3350)(8850 3300);
WIRE 16 -1 (8850 3350)(8650 3350);
WIRE 16 -1 (8850 3300)(8650 3300);
WIRE 16 -1 (10450 4875)(10450 4900);
WIRE 16 -1 (10450 4875)(10850 4875);
WIRE 16 -1 (10450 4800)(10450 4875);
WIRE 16 -1 (10850 4875)(10850 4775);
WIRE 16 -1 (11650 4325)(11650 4400);
WIRE 16 -1 (11650 4400)(11250 4400);
WIRE 16 -1 (11650 4575)(11650 4400);
WIRE 16 -1 (11250 4400)(11250 4600);
WIRE 16 -1 (7375 3975)(7375 3550);
WIRE 16 -1 (7850 3550)(7375 3550);
WIRE 16 -1 (8725 4150)(8725 3600);
WIRE 16 -1 (8725 3600)(8650 3600);
WIRE 16 -1 (7650 3800)(7650 4000);
WIRE 16 -1 (7650 3800)(7650 3750);
WIRE 16 -1 (7850 3800)(7650 3800);
WIRE 16 -1 (7650 3750)(7650 3700);
WIRE 16 -1 (7650 3750)(7850 3750);
WIRE 16 -1 (7650 3700)(7850 3700);
WIRE 16 -1 (9200 3850)(9200 4175);
WIRE 16 -1 (9200 3850)(8975 3850);
WIRE 16 -1 (8975 3850)(8975 3800);
WIRE 16 -1 (8650 3850)(8975 3850);
WIRE 16 -1 (8975 3800)(8975 3750);
WIRE 16 -1 (8650 3800)(8975 3800);
WIRE 16 -1 (8650 3750)(8975 3750);
WIRE 16 -1 (10450 4175)(10450 4150);
WIRE 16 -1 (10450 4150)(10850 4150);
WIRE 16 -1 (10450 4150)(10450 4075);
WIRE 16 -1 (11225 4150)(10850 4150);
WIRE 16 -1 (10850 4150)(10850 4050);
WIRE 16 -1 (11650 4150)(11225 4150);
WIRE 16 -1 (11225 4150)(11225 4050);
WIRE 16 -1 (11650 4150)(11650 4050);
WIRE 16 -1 (11250 4875)(11250 4900);
WIRE 16 -1 (11250 4875)(11650 4875);
WIRE 16 -1 (11250 4800)(11250 4875);
WIRE 16 -1 (11650 4875)(11650 4775);
WIRE 16 -1 (10050 3650)(10050 3700);
WIRE 16 -1 (10050 3700)(9650 3700);
WIRE 16 -1 (10050 3850)(10050 3700);
WIRE 16 -1 (9650 3700)(9650 3850);
WIRE 16 -1 (9650 4150)(9650 4250);
WIRE 16 -1 (9650 4150)(10050 4150);
WIRE 16 -1 (9650 4000)(9650 4150);
WIRE 16 -1 (10050 4150)(10050 4050);
WIRE 16 -1 (6300 4200)(6300 4100);
WIRE 16 -1 (10850 4325)(10850 4400);
WIRE 16 -1 (10850 4400)(10450 4400);
WIRE 16 -1 (10850 4575)(10850 4400);
WIRE 16 -1 (10450 4400)(10450 4600);
WIRE 17 -1 (10100 2575)(10975 2575);
FORCEPROP 0 LAST SIG_NAME P3E_OCP_CPU0_PE3_C_TXP<15:8>
J 0
(10300 2585);
DISPLAY 0.617021 (10300 2585);
PAINT ORANGE (10300 2585);
WIRE 17 -1 (10100 2575)(10100 2525);
WIRE 17 -1 (10100 2325)(10100 2525);
WIRE 17 -1 (10100 1325)(10100 1125);
WIRE 17 -1 (10100 1325)(10100 1525);
WIRE 17 -1 (10100 2325)(10100 2125);
WIRE 17 -1 (10100 2125)(10100 1925);
WIRE 17 -1 (10100 1525)(10100 1725);
WIRE 17 -1 (10100 1725)(10100 1925);
WIRE 17 -1 (10300 2500)(10975 2500);
WIRE 17 -1 (10300 2500)(10300 2475);
FORCEPROP 0 LAST SIG_NAME P3E_OCP_CPU0_PE3_C_TXN<15:8>
J 0
(10300 2510);
DISPLAY 0.617021 (10300 2510);
PAINT ORANGE (10300 2510);
WIRE 17 -1 (10300 2475)(10300 2275);
WIRE 17 -1 (10300 2075)(10300 2275);
WIRE 17 -1 (10300 1075)(10300 1275);
WIRE 17 -1 (10300 1875)(10300 2075);
WIRE 17 -1 (10300 1675)(10300 1875);
WIRE 17 -1 (10300 1275)(10300 1475);
WIRE 17 -1 (10300 1475)(10300 1675);
WIRE 17 -1 (6200 2575)(5200 2575);
FORCEPROP 2 LAST SIG_NAME P3E_CPU0_PE3_OCP_RXN<15:8>
J 0
(5197 2585);
DISPLAY 0.617021 (5197 2585);
PAINT ORANGE (5197 2585);
WIRE 17 -1 (6200 2575)(6200 2375);
WIRE 17 -1 (6200 2375)(6200 2175);
WIRE 17 -1 (6200 2175)(6200 1975);
WIRE 17 -1 (6200 1975)(6200 1775);
WIRE 17 -1 (6200 1175)(6200 975);
WIRE 17 -1 (6200 1375)(6200 1175);
WIRE 17 -1 (6200 1775)(6200 1575);
WIRE 17 -1 (6200 1575)(6200 1375);
WIRE 17 -1 (6375 1225)(6375 1025);
WIRE 17 -1 (6375 1425)(6375 1225);
WIRE 17 -1 (6375 1625)(6375 1425);
WIRE 17 -1 (6375 1825)(6375 1625);
WIRE 17 -1 (6375 1825)(6375 2025);
WIRE 17 -1 (6375 2225)(6375 2025);
WIRE 17 -1 (6375 2425)(6375 2225);
WIRE 17 -1 (6375 2625)(5200 2625);
FORCEPROP 2 LAST SIG_NAME P3E_CPU0_PE3_OCP_RXP<15:8>
J 0
(5200 2636);
DISPLAY 0.617021 (5200 2636);
PAINT ORANGE (5200 2636);
WIRE 17 -1 (6375 2625)(6375 2425);
WIRE 16 -1 (6225 4525)(5350 4525);
WIRE 16 -1 (5350 5000)(5350 4525);
WIRE 16 -1 (4500 4525)(5350 4525);
WIRE 16 -1 (4200 4525)(4500 4525);
WIRE 16 -1 (6900 4525)(6225 4525);
WIRE 16 -1 (6225 5000)(6225 4525);
WIRE 16 -1 (6225 5000)(5350 5000);
WIRE 16 -1 (6900 5000)(6225 5000);
WIRE 16 -1 (6900 5000)(6900 4525);
WIRE 16 -1 (7600 4525)(6900 4525);
WIRE 16 -1 (4200 4625)(4200 4525);
WIRE 16 -1 (4500 5000)(4500 4525);
WIRE 16 -1 (4500 5000)(5350 5000);
WIRE 16 -1 (4200 5000)(4500 5000);
WIRE 16 -1 (4200 4625)(8975 4625);
WIRE 16 -1 (8975 4625)(8975 4525);
WIRE 16 -1 (4200 4725)(4200 4625);
WIRE 16 -1 (8250 4525)(7600 4525);
WIRE 16 -1 (8975 4525)(8250 4525);
WIRE 16 -1 (7600 5000)(6900 5000);
WIRE 16 -1 (7600 5000)(7600 4525);
WIRE 16 -1 (8250 5000)(7600 5000);
WIRE 16 -1 (8250 5000)(8250 4525);
WIRE 16 -1 (4200 4725)(8975 4725);
WIRE 16 -1 (8975 4625)(8975 4725);
WIRE 16 -1 (4200 4725)(4200 4825);
WIRE 16 -1 (4200 5000)(4200 4825);
WIRE 16 -1 (4200 4825)(8975 4825);
WIRE 16 -1 (8975 4725)(8975 4825);
WIRE 16 -1 (8975 5000)(8250 5000);
WIRE 16 -1 (8975 5000)(8975 4825);
WIRE 16 -1 (7850 1200)(6475 1200);
WIRE 16 -1 (8650 1300)(10000 1300);
WIRE 16 -1 (8650 1500)(10000 1500);
WIRE 16 -1 (8650 1700)(10000 1700);
WIRE 16 -1 (8650 1100)(10000 1100);
WIRE 16 -1 (8650 1050)(10200 1050);
WIRE 16 -1 (7850 1000)(6475 1000);
WIRE 16 -1 (7850 950)(6300 950);
WIRE 16 -1 (7850 1150)(6300 1150);
WIRE 16 -1 (8650 900)(9850 900);
FORCEPROP 0 LAST SIG_NAME FM_OCP_MEZZA_PRES_N
J 1
(9388 910);
DISPLAY 0.617021 (9388 910);
PAINT ORANGE (9388 910);
WIRE 3 682 (9950 4200)(9950 3650);
WIRE 3 682 (9550 4200)(9950 4200);
WIRE 3 682 (9950 3650)(9550 3650);
WIRE 3 682 (9550 3650)(9550 4200);
WIRE 16 -1 (8650 2700)(9700 2700);
FORCEPROP 0 LAST SIG_NAME CLK_100M_MEZZ1_DP
J 1
(9213 2710);
DISPLAY 0.617021 (9213 2710);
PAINT ORANGE (9213 2710);
WIRE 16 -1 (8650 2650)(9700 2650);
FORCEPROP 0 LAST SIG_NAME CLK_100M_MEZZ1_DN
J 1
(9213 2660);
DISPLAY 0.617021 (9213 2660);
PAINT ORANGE (9213 2660);
WIRE 16 -1 (8650 2500)(10000 2500);
WIRE 16 -1 (8650 2450)(10200 2450);
WIRE 16 -1 (8650 2300)(10000 2300);
WIRE 16 -1 (8650 2250)(10200 2250);
WIRE 16 -1 (8650 2100)(10000 2100);
WIRE 16 -1 (8650 2050)(10200 2050);
WIRE 16 -1 (8650 1650)(10200 1650);
WIRE 16 -1 (6300 3850)(6300 3800);
WIRE 16 -1 (6300 3900)(6300 3850);
WIRE 16 -1 (6300 3850)(7850 3850);
FORCEPROP 0 LAST SIG_NAME FM_MEZZA_PRSNT1_N
J 1
(6938 3860);
DISPLAY 0.617021 (6938 3860);
PAINT ORANGE (6938 3860);
FORCEPROP 2 LASTPROP $XRERR UNIQUE?
J 0
(6698 3860);
DISPLAY 0.638298 (6698 3860);
PAINT MONO (6698 3860);
DISPLAY INVISIBLE (6698 3860);
WIRE 3 2175 (6050 3350)(6600 3350);
WIRE 3 2175 (6600 4350)(6600 3350);
WIRE 3 2175 (6050 4350)(6050 3350);
WIRE 3 2175 (6050 4350)(6600 4350);
WIRE 16 -1 (7850 3200)(6475 3200);
FORCEPROP 0 LAST SIG_NAME RMII_BMC_OCP_CRSDV_R
J 0
(6875 3210);
DISPLAY 0.617021 (6875 3210);
PAINT ORANGE (6875 3210);
FORCEPROP 2 LASTPROP $XRERR UNIQUE?
J 0
(6635 3210);
DISPLAY 0.638298 (6635 3210);
PAINT MONO (6635 3210);
DISPLAY INVISIBLE (6635 3210);
WIRE 16 -1 (7850 2600)(6875 2600);
FORCEPROP 0 LAST SIG_NAME CLK_100M_MEZZ2_DP
J 0
(6875 2610);
DISPLAY 0.617021 (6875 2610);
PAINT ORANGE (6875 2610);
WIRE 16 -1 (7850 2750)(6800 2750);
FORCEPROP 0 LAST SIG_NAME RMII_BMC_OCP_RXD1_R
J 0
(6875 2760);
DISPLAY 0.617021 (6875 2760);
PAINT ORANGE (6875 2760);
FORCEPROP 2 LASTPROP $XRERR UNIQUE?
J 0
(6635 2760);
DISPLAY 0.638298 (6635 2760);
PAINT MONO (6635 2760);
DISPLAY INVISIBLE (6635 2760);
WIRE 16 -1 (6475 2800)(7850 2800);
FORCEPROP 0 LAST SIG_NAME RMII_BMC_OCP_RXD0_R
J 0
(6875 2810);
DISPLAY 0.617021 (6875 2810);
PAINT ORANGE (6875 2810);
FORCEPROP 2 LASTPROP $XRERR UNIQUE?
J 0
(6635 2810);
DISPLAY 0.638298 (6635 2810);
PAINT MONO (6635 2810);
DISPLAY INVISIBLE (6635 2810);
WIRE 16 -1 (5200 2750)(6600 2750);
FORCEPROP 2 LAST SIG_NAME RMII_BMC_OCP_RXD1
J 0
(5200 2760);
DISPLAY 0.617021 (5200 2760);
PAINT ORANGE (5200 2760);
WIRE 16 -1 (5200 2800)(6275 2800);
FORCEPROP 2 LAST SIG_NAME RMII_BMC_OCP_RXD0
J 0
(5200 2810);
DISPLAY 0.617021 (5200 2810);
PAINT ORANGE (5200 2810);
WIRE 16 -1 (5200 3050)(5900 3050);
FORCEPROP 0 LAST SIG_NAME RST_PCIE_CPU_DEV0_N
J 0
(5200 3060);
DISPLAY 0.617021 (5200 3060);
PAINT ORANGE (5200 3060);
WIRE 16 -1 (7850 3050)(6100 3050);
FORCEPROP 0 LAST SIG_NAME RST_PCIE_CPU_DEV0_R_N
J 0
(6850 3060);
DISPLAY 0.617021 (6850 3060);
PAINT ORANGE (6850 3060);
FORCEPROP 2 LASTPROP $XRERR UNIQUE?
J 0
(6610 3060);
DISPLAY 0.638298 (6610 3060);
PAINT MONO (6610 3060);
DISPLAY INVISIBLE (6610 3060);
WIRE 16 -1 (7850 3100)(6875 3100);
FORCEPROP 0 LAST SIG_NAME RMII_BMC_OCP_TXEN
J 0
(6875 3110);
DISPLAY 0.617021 (6875 3110);
PAINT ORANGE (6875 3110);
WIRE 16 -1 (7850 3150)(6875 3150);
FORCEPROP 0 LAST SIG_NAME CLK_50M_CKMNG_OCP
J 0
(6875 3160);
DISPLAY 0.617021 (6875 3160);
PAINT ORANGE (6875 3160);
WIRE 16 -1 (7850 2200)(6475 2200);
WIRE 16 -1 (7850 2150)(6300 2150);
WIRE 16 -1 (7850 2000)(6475 2000);
WIRE 16 -1 (7850 1950)(6300 1950);
WIRE 16 -1 (10350 3000)(11050 3000);
FORCEPROP 2 LAST SIG_NAME RMII_BMC_OCP_RXER
J 0
(10465 3010);
DISPLAY 0.617021 (10465 3010);
PAINT ORANGE (10465 3010);
WIRE 16 -1 (7850 3000)(6875 3000);
FORCEPROP 0 LAST SIG_NAME SMB_OCP_LAN_STBY_LVC3_SCL
J 0
(6875 3010);
DISPLAY 0.617021 (6875 3010);
PAINT ORANGE (6875 3010);
WIRE 16 -1 (7850 2950)(6875 2950);
FORCEPROP 0 LAST SIG_NAME SMB_OCP_LAN_STBY_LVC3_SDA
J 0
(6875 2960);
DISPLAY 0.617021 (6875 2960);
PAINT ORANGE (6875 2960);
WIRE 16 -1 (8650 3050)(9700 3050);
FORCEPROP 0 LAST SIG_NAME FM_PE_OCP_WAKE_N
J 0
(9125 3060);
DISPLAY 0.617021 (9125 3060);
PAINT ORANGE (9125 3060);
WIRE 16 -1 (8650 3100)(9700 3100);
FORCEPROP 0 LAST SIG_NAME SMB_OCP_FRU_STBY_LVC3_SDA
J 0
(9125 3110);
DISPLAY 0.617021 (9125 3110);
PAINT ORANGE (9125 3110);
WIRE 16 -1 (8650 3150)(9700 3150);
FORCEPROP 0 LAST SIG_NAME SMB_OCP_FRU_STBY_LVC3_SCL
J 0
(9125 3160);
DISPLAY 0.617021 (9125 3160);
PAINT ORANGE (9125 3160);
WIRE 16 -1 (8650 3200)(9700 3200);
FORCEPROP 0 LAST SIG_NAME IRQ_MEZZ_LAN_ALERT_N
J 0
(9125 3210);
DISPLAY 0.617021 (9125 3210);
PAINT ORANGE (9125 3210);
WIRE 16 -1 (5200 3200)(6275 3200);
FORCEPROP 2 LAST SIG_NAME RMII_BMC_OCP_CRSDV
J 0
(5200 3210);
DISPLAY 0.617021 (5200 3210);
PAINT ORANGE (5200 3210);
WIRE 16 -1 (7850 1400)(6475 1400);
WIRE 16 -1 (7850 1550)(6300 1550);
WIRE 16 -1 (7850 1600)(6475 1600);
WIRE 16 -1 (7850 1750)(6300 1750);
WIRE 16 -1 (7850 1800)(6475 1800);
WIRE 16 -1 (7850 2550)(6875 2550);
FORCEPROP 0 LAST SIG_NAME CLK_100M_MEZZ2_DN
J 0
(6875 2560);
DISPLAY 0.617021 (6875 2560);
PAINT ORANGE (6875 2560);
WIRE 16 -1 (7850 2400)(6475 2400);
WIRE 16 -1 (7850 2350)(6300 2350);
WIRE 16 -1 (7850 1350)(6300 1350);
WIRE 16 -1 (8650 1850)(10200 1850);
WIRE 16 -1 (8650 3000)(10150 3000);
FORCEPROP 0 LAST SIG_NAME RMII_BMC_OCP_RXER_R
J 0
(9125 3010);
DISPLAY 0.617021 (9125 3010);
PAINT ORANGE (9125 3010);
FORCEPROP 2 LASTPROP $XRERR UNIQUE?
J 0
(8885 3010);
DISPLAY 0.638298 (8885 3010);
PAINT MONO (8885 3010);
DISPLAY INVISIBLE (8885 3010);
WIRE 16 -1 (8650 1250)(10200 1250);
WIRE 16 -1 (8650 1450)(10200 1450);
WIRE 16 -1 (8650 1900)(10000 1900);
WIRE 16 -1 (8650 2850)(9700 2850);
FORCEPROP 0 LAST SIG_NAME RMII_BMC_OCP_TXD1
J 0
(9125 2860);
DISPLAY 0.617021 (9125 2860);
PAINT ORANGE (9125 2860);
WIRE 16 -1 (8650 2900)(9700 2900);
FORCEPROP 0 LAST SIG_NAME RMII_BMC_OCP_TXD0
J 0
(9125 2910);
DISPLAY 0.617021 (9125 2910);
PAINT ORANGE (9125 2910);
DOT 1 (7525 2900);
DOT 1 (7525 2850);
DOT 1 (8975 3250);
DOT 1 (8975 2800);
DOT 1 (8975 2950);
DOT 1 (8975 3500);
DOT 1 (8975 1950);
DOT 1 (8975 1800);
DOT 1 (8975 1600);
DOT 1 (6225 4525);
DOT 1 (8975 2750);
DOT 1 (8975 1350);
DOT 1 (8975 1200);
DOT 1 (8975 1150);
DOT 1 (7600 4525);
DOT 1 (8250 4525);
DOT 1 (10050 3700);
DOT 1 (11650 4400);
DOT 1 (11250 4875);
DOT 1 (11225 3700);
DOT 1 (11650 3700);
DOT 1 (11225 4150);
DOT 1 (10850 4150);
DOT 1 (10450 4875);
DOT 1 (10850 4400);
DOT 1 (8975 4825);
DOT 1 (8975 4725);
DOT 1 (8975 4625);
DOT 1 (8250 5000);
DOT 1 (7600 5000);
DOT 1 (6900 5000);
DOT 1 (6225 5000);
DOT 1 (5350 4525);
DOT 1 (5350 5000);
DOT 1 (4500 5000);
DOT 1 (4200 4825);
DOT 1 (4200 4625);
DOT 1 (4200 4725);
DOT 1 (7525 3600);
DOT 1 (7650 3800);
DOT 1 (7650 3750);
DOT 1 (7525 3500);
DOT 1 (7000 3300);
DOT 1 (7525 2500);
DOT 1 (7525 2450);
DOT 1 (7525 2300);
DOT 1 (7525 2250);
DOT 1 (7525 2100);
DOT 1 (7525 2050);
DOT 1 (7525 1700);
DOT 1 (7525 1650);
DOT 1 (7525 1500);
DOT 1 (7525 1450);
DOT 1 (7525 1300);
DOT 1 (7525 1250);
DOT 1 (7525 1050);
DOT 1 (7525 1100);
DOT 1 (7525 900);
DOT 1 (8975 3650);
DOT 1 (8975 3800);
DOT 1 (8975 3850);
DOT 1 (8975 3550);
DOT 1 (8850 3400);
DOT 1 (8975 2350);
DOT 1 (8975 2150);
DOT 1 (8975 2200);
DOT 1 (8975 2000);
DOT 1 (8975 950);
DOT 1 (8975 1000);
DOT 1 (8975 2600);
DOT 1 (8850 3450);
DOT 1 (8850 3350);
DOT 1 (7525 3450);
DOT 1 (7525 1900);
DOT 1 (8975 1550);
DOT 1 (6900 4525);
DOT 1 (7000 3350);
DOT 1 (6300 3850);
DOT 1 (8975 1400);
DOT 1 (8975 2550);
DOT 1 (7525 2700);
DOT 1 (8975 2400);
DOT 1 (9650 4150);
DOT 1 (10450 4150);
DOT 1 (10850 3700);
DOT 1 (7525 1850);
DOT 1 (7525 2650);
DOT 1 (8975 1750);
DOT 1 (7000 3400);
DOT 1 (4500 4525);
FORCENOTE
FCI PLUG # ON OCP MEZZ
(4550 4925) 0;
DISPLAY LEFT (4550 4925);
DISPLAY 1.021277 (4550 4925);
PAINT PURPLE (4550 4925);
FORCENOTE
TP FAB1  ADD R9W1  10K OHM AND CHANGE R9B7 TO 887 OHM1210
(5781 4397) 0;
DISPLAY LEFT (5781 4397);
DISPLAY 1.021277 (5781 4397);
PAINT RED (5781 4397);
FORCENOTE
61082-081402LF
(4550 4650) 0;
DISPLAY LEFT (4550 4650);
DISPLAY 1.021277 (4550 4650);
PAINT PURPLE (4550 4650);
FORCENOTE
CONN
(4225 4925) 0;
DISPLAY LEFT (4225 4925);
DISPLAY 1.021277 (4225 4925);
PAINT PURPLE (4225 4925);
FORCENOTE
E67482-008
(8275 4650) 0;
DISPLAY LEFT (8275 4650);
DISPLAY 1.021277 (8275 4650);
PAINT PURPLE (8275 4650);
FORCENOTE
B (80P)
(4225 4650) 0;
DISPLAY LEFT (4225 4650);
DISPLAY 1.021277 (4225 4650);
PAINT PURPLE (4225 4650);
FORCENOTE
FCI RECPT IPN ON CC
(6925 4925) 0;
DISPLAY LEFT (6925 4925);
DISPLAY 1.021277 (6925 4925);
PAINT PURPLE (6925 4925);
FORCENOTE
(5/8MM STACK)
(6275 4850) 0;
DISPLAY LEFT (6275 4850);
DISPLAY 1.021277 (6275 4850);
PAINT PURPLE (6275 4850);
FORCENOTE
61082-121402LF
(6275 4750) 0;
DISPLAY LEFT (6275 4750);
DISPLAY 1.021277 (6275 4750);
PAINT PURPLE (6275 4750);
FORCENOTE
61082-081402LF
(6275 4650) 0;
DISPLAY LEFT (6275 4650);
DISPLAY 1.021277 (6275 4650);
PAINT PURPLE (6275 4650);
FORCENOTE
FCI RECPT # ON CC
(6275 4925) 0;
DISPLAY LEFT (6275 4925);
DISPLAY 1.021277 (6275 4925);
PAINT PURPLE (6275 4925);
FORCENOTE
10135583-642402LF
(7625 4550) 0;
DISPLAY LEFT (7625 4550);
DISPLAY 1.021277 (7625 4550);
PAINT PURPLE (7625 4550);
FORCENOTE
MATED HT CONNECTOR P/NS
(4225 5025) 0;
DISPLAY LEFT (4225 5025);
DISPLAY 1.021277 (4225 5025);
PAINT PURPLE (4225 5025);
FORCENOTE
H87568-002
(8275 4550) 0;
DISPLAY LEFT (8275 4550);
DISPLAY 1.021277 (8275 4550);
PAINT PURPLE (8275 4550);
FORCENOTE
E67482-006
(6950 4650) 0;
DISPLAY LEFT (6950 4650);
DISPLAY 1.021277 (6950 4650);
PAINT PURPLE (6950 4650);
FORCENOTE
FCI RECPT IPN ON CC
(8275 4925) 0;
DISPLAY LEFT (8275 4925);
DISPLAY 1.021277 (8275 4925);
PAINT PURPLE (8275 4925);
FORCENOTE
FCI RECPT # ON CC
(7625 4925) 0;
DISPLAY LEFT (7625 4925);
DISPLAY 1.021277 (7625 4925);
PAINT PURPLE (7625 4925);
FORCENOTE
(12MM STACK)
(7625 4850) 0;
DISPLAY LEFT (7625 4850);
DISPLAY 1.021277 (7625 4850);
PAINT PURPLE (7625 4850);
FORCENOTE
61082-122402LF
(7625 4750) 0;
DISPLAY LEFT (7625 4750);
DISPLAY 1.021277 (7625 4750);
PAINT PURPLE (7625 4750);
FORCENOTE
ROOM=IO_SLOT
(4150 400) 0;
DISPLAY LEFT (4150 400);
DISPLAY 2.000000 (4150 400);
PAINT PURPLE (4150 400);
FORCENOTE
TO CPU0
(5025 2400) 0;
DISPLAY LEFT (5025 2400);
DISPLAY 1.021277 (5025 2400);
PAINT PURPLE (5025 2400);
FORCENOTE
C (64P)
(4225 4550) 0;
DISPLAY LEFT (4225 4550);
DISPLAY 1.021277 (4225 4550);
PAINT PURPLE (4225 4550);
FORCENOTE
61083-124402LF
(5400 4750) 0;
DISPLAY LEFT (5400 4750);
DISPLAY 1.021277 (5400 4750);
PAINT PURPLE (5400 4750);
FORCENOTE
(8/12 MM STACK)
(5400 4850) 0;
DISPLAY LEFT (5400 4850);
DISPLAY 1.021277 (5400 4850);
PAINT PURPLE (5400 4850);
FORCENOTE
FCI PLUG # ON OCP MEZZ
(5400 4925) 0;
DISPLAY LEFT (5400 4925);
DISPLAY 1.021277 (5400 4925);
PAINT PURPLE (5400 4925);
FORCENOTE
61082-082402LF
(7625 4650) 0;
DISPLAY LEFT (7625 4650);
DISPLAY 1.021277 (7625 4650);
PAINT PURPLE (7625 4650);
FORCENOTE
10135584-644402LF
(5400 4550) 0;
DISPLAY LEFT (5400 4550);
DISPLAY 1.021277 (5400 4550);
PAINT PURPLE (5400 4550);
FORCENOTE
A28699-010
(6950 4750) 0;
DISPLAY LEFT (6950 4750);
DISPLAY 1.021277 (6950 4750);
PAINT PURPLE (6950 4750);
FORCENOTE
A28699-020
(8275 4750) 0;
DISPLAY LEFT (8275 4750);
DISPLAY 1.021277 (8275 4750);
PAINT PURPLE (8275 4750);
FORCENOTE
(12 MM STACK)
(8275 4850) 0;
DISPLAY LEFT (8275 4850);
DISPLAY 1.021277 (8275 4850);
PAINT PURPLE (8275 4850);
FORCENOTE
10135583-641402LF
(6275 4550) 0;
DISPLAY LEFT (6275 4550);
DISPLAY 1.021277 (6275 4550);
PAINT PURPLE (6275 4550);
FORCENOTE
10135584-641402LF
(4550 4550) 0;
DISPLAY LEFT (4550 4550);
DISPLAY 1.021277 (4550 4550);
PAINT PURPLE (4550 4550);
FORCENOTE
A (120P)
(4225 4750) 0;
DISPLAY LEFT (4225 4750);
DISPLAY 1.021277 (4225 4750);
PAINT PURPLE (4225 4750);
FORCENOTE
(5/8MM STACK)
(6950 4850) 0;
DISPLAY LEFT (6950 4850);
DISPLAY 1.021277 (6950 4850);
PAINT PURPLE (6950 4850);
FORCENOTE
FROM CPU0
(10900 2325) 0;
DISPLAY LEFT (10900 2325);
DISPLAY 1.021277 (10900 2325);
PAINT PURPLE (10900 2325);
FORCENOTE
0.26V~0.27V
(5875 3825) 0;
DISPLAY LEFT (5875 3825);
DISPLAY 1.021277 (5875 3825);
PAINT PURPLE (5875 3825);
FORCENOTE
TP FAB1 CHANGE PN 0310
(9550 3550) 0;
DISPLAY LEFT (9550 3550);
DISPLAY 0.808511 (9550 3550);
PAINT RED (9550 3550);
FORCENOTE
H87568-001
(6950 4550) 0;
DISPLAY LEFT (6950 4550);
DISPLAY 1.021277 (6950 4550);
PAINT PURPLE (6950 4550);
FORCENOTE
61083-084402LF
(5400 4650) 0;
DISPLAY LEFT (5400 4650);
DISPLAY 1.021277 (5400 4650);
PAINT PURPLE (5400 4650);
FORCENOTE
61083-121402LF
(4550 4750) 0;
DISPLAY LEFT (4550 4750);
DISPLAY 1.021277 (4550 4750);
PAINT PURPLE (4550 4750);
FORCENOTE
(5MM STACK)
(4550 4850) 0;
DISPLAY LEFT (4550 4850);
DISPLAY 1.021277 (4550 4850);
PAINT PURPLE (4550 4850);
QUIT
